FILE_TYPE = MACRO_DRAWING;
SET COLOR_WIRE YELLOW;
SET COLOR_PROP MONO;
SET COLOR_DOT WHITE;
SET COLOR_ARC YELLOW;
SET COLOR_BODY GREEN;
SET COLOR_NOTE MONO;
SET PROP_DISPLAY VALUE;
SET PAGE_NUMBER P120;
FORCEADD OFFPAGE..6
R 2
(-1575 3850);
FORCEPROP 2 LAST $XR0 138 
J 0
(-1361 3850);
DISPLAY 0.638298 (-1361 3850);
PAINT MONO (-1361 3850);
FORCEPROP 2 LAST CDS_LIB mstr_standard
J 2
(-1575 3850);
DISPLAY 1.212766 (-1575 3850);
PAINT ORANGE (-1575 3850);
DISPLAY INVISIBLE (-1575 3850);
FORCEPROP 1 LAST OFFPAGE TRUE
J 2
(-1900 3725);
PAINT GREEN (-1900 3725);
DISPLAY INVISIBLE (-1900 3725);
FORCEPROP 1 LAST COMMENT_BODY TRUE
J 2
(-1675 3775);
DISPLAY 1.404255 (-1675 3775);
PAINT PEACH (-1675 3775);
DISPLAY INVISIBLE (-1675 3775);
FORCEPROP 2 LAST PATH I10
J 0
(-1375 3925);
DISPLAY 1.021277 (-1375 3925);
PAINT ORANGE (-1375 3925);
DISPLAY INVISIBLE (-1375 3925);
FORCEADD OFFPAGE..1
(-7200 3950);
FORCEPROP 2 LAST $XR0 92 
J 0
(-7451 3950);
DISPLAY 0.638298 (-7451 3950);
PAINT MONO (-7451 3950);
FORCEPROP 2 LAST $XR2 190 
J 0
(-7691 3950);
DISPLAY 0.638298 (-7691 3950);
PAINT MONO (-7691 3950);
FORCEPROP 2 LAST $XR1 147 
J 0
(-7571 3950);
DISPLAY 0.638298 (-7571 3950);
PAINT MONO (-7571 3950);
FORCEPROP 2 LAST CDS_LIB mstr_standard
J 0
(-7200 3950);
PAINT ORANGE (-7200 3950);
DISPLAY INVISIBLE (-7200 3950);
FORCEPROP 1 LAST OFFPAGE TRUE
J 0
(-6875 3825);
PAINT GREEN (-6875 3825);
DISPLAY INVISIBLE (-6875 3825);
FORCEPROP 1 LAST COMMENT_BODY TRUE
J 0
(-7075 3850);
DISPLAY 1.404255 (-7075 3850);
PAINT PEACH (-7075 3850);
DISPLAY INVISIBLE (-7075 3850);
FORCEPROP 2 LAST PATH I111
J 0
(-7150 4025);
DISPLAY 1.021277 (-7150 4025);
PAINT ORANGE (-7150 4025);
DISPLAY INVISIBLE (-7150 4025);
FORCEADD OFFPAGE..5
(-7200 4000);
FORCEPROP 2 LAST $XR0 145 
J 0
(-7485 4000);
DISPLAY 0.638298 (-7485 4000);
PAINT MONO (-7485 4000);
FORCEPROP 2 LAST $XR1 156 
J 0
(-7605 4000);
DISPLAY 0.638298 (-7605 4000);
PAINT MONO (-7605 4000);
FORCEPROP 2 LAST $XR2 ?
J 0
(-7605 4000);
DISPLAY 0.638298 (-7605 4000);
PAINT MONO (-7605 4000);
FORCEPROP 2 LAST CDS_LIB mstr_standard
J 0
(-7200 4000);
PAINT ORANGE (-7200 4000);
DISPLAY INVISIBLE (-7200 4000);
FORCEPROP 1 LAST OFFPAGE TRUE
J 0
(-6875 3875);
DISPLAY 0.872340 (-6875 3875);
PAINT GREEN (-6875 3875);
DISPLAY INVISIBLE (-6875 3875);
FORCEPROP 1 LAST COMMENT_BODY TRUE
J 0
(-7100 3925);
DISPLAY 0.872340 (-7100 3925);
PAINT GREEN (-7100 3925);
DISPLAY INVISIBLE (-7100 3925);
FORCEPROP 2 LAST PATH I113
J 0
(-7150 4075);
DISPLAY 1.021277 (-7150 4075);
PAINT ORANGE (-7150 4075);
DISPLAY INVISIBLE (-7150 4075);
FORCEADD OFFPAGE..1
R 2
(-1525 4200);
FORCEPROP 2 LAST $XR0 120 
J 0
(-1339 4200);
DISPLAY 0.638298 (-1339 4200);
PAINT MONO (-1339 4200);
FORCEPROP 2 LAST $XR1 133 
J 0
(-1219 4200);
DISPLAY 0.638298 (-1219 4200);
PAINT MONO (-1219 4200);
FORCEPROP 2 LAST $XR2 145 
J 0
(-1099 4200);
DISPLAY 0.638298 (-1099 4200);
PAINT MONO (-1099 4200);
FORCEPROP 2 LAST $XR3 ?
J 0
(-1099 4200);
DISPLAY 0.638298 (-1099 4200);
PAINT MONO (-1099 4200);
FORCEPROP 2 LAST CDS_LIB mstr_standard
J 0
(-1525 4200);
PAINT ORANGE (-1525 4200);
DISPLAY INVISIBLE (-1525 4200);
FORCEPROP 1 LAST OFFPAGE TRUE
J 2
(-1850 4075);
DISPLAY 0.872340 (-1850 4075);
PAINT GREEN (-1850 4075);
DISPLAY INVISIBLE (-1850 4075);
FORCEPROP 1 LAST COMMENT_BODY TRUE
J 2
(-1650 4100);
DISPLAY 0.872340 (-1650 4100);
PAINT GREEN (-1650 4100);
DISPLAY INVISIBLE (-1650 4100);
FORCEPROP 2 LAST PATH I115
J 0
(-1350 4275);
DISPLAY 1.021277 (-1350 4275);
PAINT ORANGE (-1350 4275);
DISPLAY INVISIBLE (-1350 4275);
FORCEADD OFFPAGE..1
R 2
(-1525 4150);
FORCEPROP 2 LAST $XR0 157 
J 0
(-1339 4150);
DISPLAY 0.638298 (-1339 4150);
PAINT MONO (-1339 4150);
FORCEPROP 2 LAST $XR1 146 
J 0
(-1219 4150);
DISPLAY 0.638298 (-1219 4150);
PAINT MONO (-1219 4150);
FORCEPROP 2 LAST CDS_LIB mstr_standard
J 0
(-1525 4150);
PAINT ORANGE (-1525 4150);
DISPLAY INVISIBLE (-1525 4150);
FORCEPROP 1 LAST OFFPAGE TRUE
J 2
(-1850 4025);
DISPLAY 0.872340 (-1850 4025);
PAINT GREEN (-1850 4025);
DISPLAY INVISIBLE (-1850 4025);
FORCEPROP 1 LAST COMMENT_BODY TRUE
J 2
(-1650 4050);
DISPLAY 0.872340 (-1650 4050);
PAINT GREEN (-1650 4050);
DISPLAY INVISIBLE (-1650 4050);
FORCEPROP 2 LAST PATH I116
J 0
(-1350 4225);
DISPLAY 1.021277 (-1350 4225);
PAINT ORANGE (-1350 4225);
DISPLAY INVISIBLE (-1350 4225);
FORCEADD OFFPAGE..1
R 2
(-1525 2950);
FORCEPROP 2 LAST $XR0 118 
J 0
(-1339 2950);
DISPLAY 0.638298 (-1339 2950);
PAINT MONO (-1339 2950);
FORCEPROP 2 LAST CDS_LIB mstr_standard
J 0
(-1525 2950);
PAINT ORANGE (-1525 2950);
DISPLAY INVISIBLE (-1525 2950);
FORCEPROP 1 LAST OFFPAGE TRUE
J 2
(-1850 2825);
DISPLAY 0.872340 (-1850 2825);
PAINT GREEN (-1850 2825);
DISPLAY INVISIBLE (-1850 2825);
FORCEPROP 1 LAST COMMENT_BODY TRUE
J 2
(-1650 2850);
DISPLAY 0.872340 (-1650 2850);
PAINT GREEN (-1650 2850);
DISPLAY INVISIBLE (-1650 2850);
FORCEPROP 2 LAST PATH I117
J 0
(-1350 3025);
DISPLAY 1.021277 (-1350 3025);
PAINT ORANGE (-1350 3025);
DISPLAY INVISIBLE (-1350 3025);
FORCEADD OFFPAGE..1
R 2
(-1525 2900);
FORCEPROP 2 LAST $XR0 133 
J 0
(-1339 2900);
DISPLAY 0.638298 (-1339 2900);
PAINT MONO (-1339 2900);
FORCEPROP 2 LAST CDS_LIB mstr_standard
J 0
(-1525 2900);
PAINT ORANGE (-1525 2900);
DISPLAY INVISIBLE (-1525 2900);
FORCEPROP 1 LAST OFFPAGE TRUE
J 2
(-1850 2775);
PAINT GREEN (-1850 2775);
DISPLAY INVISIBLE (-1850 2775);
FORCEPROP 1 LAST COMMENT_BODY TRUE
J 2
(-1650 2800);
DISPLAY 1.404255 (-1650 2800);
PAINT PEACH (-1650 2800);
DISPLAY INVISIBLE (-1650 2800);
FORCEPROP 2 LAST PATH I118
J 0
(-1350 2975);
DISPLAY 1.021277 (-1350 2975);
PAINT ORANGE (-1350 2975);
DISPLAY INVISIBLE (-1350 2975);
FORCEADD OFFPAGE..1
(-7200 3800);
FORCEPROP 2 LAST $XR0 168 
J 0
(-7452 3800);
DISPLAY 0.638298 (-7452 3800);
PAINT MONO (-7452 3800);
FORCEPROP 2 LAST $XR1 119 
J 0
(-7572 3800);
DISPLAY 0.638298 (-7572 3800);
PAINT MONO (-7572 3800);
FORCEPROP 2 LAST $XR2 147 
J 0
(-7692 3800);
DISPLAY 0.638298 (-7692 3800);
PAINT MONO (-7692 3800);
FORCEPROP 2 LAST CDS_LIB mstr_standard
J 0
(-7200 3800);
PAINT ORANGE (-7200 3800);
DISPLAY INVISIBLE (-7200 3800);
FORCEPROP 1 LAST OFFPAGE TRUE
J 0
(-6875 3675);
PAINT GREEN (-6875 3675);
DISPLAY INVISIBLE (-6875 3675);
FORCEPROP 1 LAST COMMENT_BODY TRUE
J 0
(-7075 3700);
DISPLAY 1.404255 (-7075 3700);
PAINT PEACH (-7075 3700);
DISPLAY INVISIBLE (-7075 3700);
FORCEPROP 2 LAST PATH I119
J 0
(-7150 3875);
DISPLAY 1.021277 (-7150 3875);
PAINT ORANGE (-7150 3875);
DISPLAY INVISIBLE (-7150 3875);
FORCEADD OFFPAGE..1
R 2
(-1525 3900);
FORCEPROP 2 LAST $XR0 125 
J 0
(-1339 3900);
DISPLAY 0.638298 (-1339 3900);
PAINT MONO (-1339 3900);
FORCEPROP 2 LAST CDS_LIB mstr_standard
J 0
(-1525 3900);
PAINT ORANGE (-1525 3900);
DISPLAY INVISIBLE (-1525 3900);
FORCEPROP 1 LAST OFFPAGE TRUE
J 2
(-1850 3775);
PAINT GREEN (-1850 3775);
DISPLAY INVISIBLE (-1850 3775);
FORCEPROP 1 LAST COMMENT_BODY TRUE
J 2
(-1650 3800);
DISPLAY 1.404255 (-1650 3800);
PAINT PEACH (-1650 3800);
DISPLAY INVISIBLE (-1650 3800);
FORCEPROP 2 LAST PATH I140
J 0
(-1350 3975);
DISPLAY 1.021277 (-1350 3975);
PAINT ORANGE (-1350 3975);
DISPLAY INVISIBLE (-1350 3975);
FORCEADD OFFPAGE..1
R 2
(-1525 4300);
FORCEPROP 2 LAST $XR0 185 
J 0
(-1339 4300);
DISPLAY 0.638298 (-1339 4300);
PAINT MONO (-1339 4300);
FORCEPROP 2 LAST $XR1 145 
J 0
(-1339 4300);
DISPLAY 0.638298 (-1339 4300);
PAINT MONO (-1339 4300);
FORCEPROP 2 LAST CDS_LIB mstr_standard
J 0
(-1525 4300);
PAINT ORANGE (-1525 4300);
DISPLAY INVISIBLE (-1525 4300);
FORCEPROP 1 LAST OFFPAGE TRUE
J 2
(-1850 4175);
PAINT GREEN (-1850 4175);
DISPLAY INVISIBLE (-1850 4175);
FORCEPROP 1 LAST COMMENT_BODY TRUE
J 2
(-1650 4200);
DISPLAY 1.404255 (-1650 4200);
PAINT PEACH (-1650 4200);
DISPLAY INVISIBLE (-1650 4200);
FORCEPROP 2 LAST PATH I141
J 0
(-1350 4375);
DISPLAY 1.021277 (-1350 4375);
PAINT ORANGE (-1350 4375);
DISPLAY INVISIBLE (-1350 4375);
FORCEADD OFFPAGE..2
(-1525 2650);
FORCEPROP 2 LAST $XR0 189 
J 0
(-1336 2650);
DISPLAY 0.638298 (-1336 2650);
PAINT MONO (-1336 2650);
FORCEPROP 2 LAST CDS_LIB mstr_standard
J 0
(-1525 2650);
PAINT ORANGE (-1525 2650);
DISPLAY INVISIBLE (-1525 2650);
FORCEPROP 1 LAST OFFPAGE TRUE
J 0
(-1200 2525);
DISPLAY 0.872340 (-1200 2525);
PAINT GREEN (-1200 2525);
DISPLAY INVISIBLE (-1200 2525);
FORCEPROP 1 LAST COMMENT_BODY TRUE
J 0
(-1570 2555);
DISPLAY 0.872340 (-1570 2555);
PAINT GREEN (-1570 2555);
DISPLAY INVISIBLE (-1570 2555);
FORCEPROP 2 LAST PATH I142
J 0
(-1350 2725);
DISPLAY 1.021277 (-1350 2725);
PAINT ORANGE (-1350 2725);
DISPLAY INVISIBLE (-1350 2725);
FORCEADD OFFPAGE..2
(-1550 2600);
FORCEPROP 2 LAST $XR0 189 
J 0
(-1361 2600);
DISPLAY 0.638298 (-1361 2600);
PAINT MONO (-1361 2600);
FORCEPROP 2 LAST CDS_LIB mstr_standard
J 0
(-1550 2600);
PAINT ORANGE (-1550 2600);
DISPLAY INVISIBLE (-1550 2600);
FORCEPROP 1 LAST OFFPAGE TRUE
J 0
(-1225 2475);
DISPLAY 0.872340 (-1225 2475);
PAINT GREEN (-1225 2475);
DISPLAY INVISIBLE (-1225 2475);
FORCEPROP 1 LAST COMMENT_BODY TRUE
J 0
(-1595 2505);
DISPLAY 0.872340 (-1595 2505);
PAINT GREEN (-1595 2505);
DISPLAY INVISIBLE (-1595 2505);
FORCEPROP 2 LAST PATH I143
J 0
(-1375 2675);
DISPLAY 1.021277 (-1375 2675);
PAINT ORANGE (-1375 2675);
DISPLAY INVISIBLE (-1375 2675);
FORCEADD OFFPAGE..4
(-1550 2500);
FORCEPROP 2 LAST $XR0 189 
J 0
(-1364 2500);
DISPLAY 0.638298 (-1364 2500);
PAINT MONO (-1364 2500);
FORCEPROP 2 LAST CDS_LIB mstr_standard
J 0
(-1550 2500);
PAINT ORANGE (-1550 2500);
DISPLAY INVISIBLE (-1550 2500);
FORCEPROP 1 LAST OFFPAGE TRUE
J 0
(-1225 2375);
DISPLAY 0.872340 (-1225 2375);
PAINT GREEN (-1225 2375);
DISPLAY INVISIBLE (-1225 2375);
FORCEPROP 1 LAST COMMENT_BODY TRUE
J 0
(-1575 2400);
DISPLAY 0.872340 (-1575 2400);
PAINT GREEN (-1575 2400);
DISPLAY INVISIBLE (-1575 2400);
FORCEPROP 2 LAST PATH I145
J 0
(-1375 2575);
DISPLAY 1.021277 (-1375 2575);
PAINT ORANGE (-1375 2575);
DISPLAY INVISIBLE (-1375 2575);
FORCEADD OFFPAGE..2
(-1550 2550);
FORCEPROP 2 LAST $XR0 189 
J 0
(-1361 2550);
DISPLAY 0.638298 (-1361 2550);
PAINT MONO (-1361 2550);
FORCEPROP 2 LAST CDS_LIB mstr_standard
J 0
(-1550 2550);
PAINT ORANGE (-1550 2550);
DISPLAY INVISIBLE (-1550 2550);
FORCEPROP 1 LAST OFFPAGE TRUE
J 0
(-1225 2425);
DISPLAY 0.872340 (-1225 2425);
PAINT GREEN (-1225 2425);
DISPLAY INVISIBLE (-1225 2425);
FORCEPROP 1 LAST COMMENT_BODY TRUE
J 0
(-1595 2455);
DISPLAY 0.872340 (-1595 2455);
PAINT GREEN (-1595 2455);
DISPLAY INVISIBLE (-1595 2455);
FORCEPROP 2 LAST PATH I146
J 0
(-1375 2625);
DISPLAY 1.021277 (-1375 2625);
PAINT ORANGE (-1375 2625);
DISPLAY INVISIBLE (-1375 2625);
FORCEADD LBG_CORE_QAT_EXT_D..7
(-3975 2800);
FORCEPROP 2 LASTPIN (-2375 1700) $PN BN3
J 0
(-2365 1710);
DISPLAY 0.617021 (-2365 1710);
PAINT ORANGE (-2365 1710);
FORCEPROP 2 LASTPIN (-2375 1650) $PN BM4
J 0
(-2365 1660);
DISPLAY 0.617021 (-2365 1660);
PAINT ORANGE (-2365 1660);
FORCEPROP 2 LASTPIN (-2375 1600) $PN BM2
J 0
(-2365 1610);
DISPLAY 0.617021 (-2365 1610);
PAINT ORANGE (-2365 1610);
FORCEPROP 2 LASTPIN (-2375 1550) $PN CA13
J 0
(-2365 1560);
DISPLAY 0.617021 (-2365 1560);
PAINT ORANGE (-2365 1560);
FORCEPROP 2 LASTPIN (-2375 1500) $PN BU6
J 0
(-2365 1510);
DISPLAY 0.617021 (-2365 1510);
PAINT ORANGE (-2365 1510);
FORCEPROP 2 LASTPIN (-2375 1450) $PN BL3
J 0
(-2365 1460);
DISPLAY 0.617021 (-2365 1460);
PAINT ORANGE (-2365 1460);
FORCEPROP 2 LASTPIN (-2375 1400) $PN BK2
J 0
(-2365 1410);
DISPLAY 0.617021 (-2365 1410);
PAINT ORANGE (-2365 1410);
FORCEPROP 2 LASTPIN (-2375 1350) $PN BP4
J 0
(-2365 1360);
DISPLAY 0.617021 (-2365 1360);
PAINT ORANGE (-2365 1360);
FORCEPROP 2 LASTPIN (-2375 2400) $PN BV14
J 0
(-2365 2410);
DISPLAY 0.617021 (-2365 2410);
PAINT ORANGE (-2365 2410);
FORCEPROP 2 LASTPIN (-2375 2350) $PN BY12
J 0
(-2365 2360);
DISPLAY 0.617021 (-2365 2360);
PAINT ORANGE (-2365 2360);
FORCEPROP 2 LASTPIN (-2375 2300) $PN BV12
J 0
(-2365 2310);
DISPLAY 0.617021 (-2365 2310);
PAINT ORANGE (-2365 2310);
FORCEPROP 2 LASTPIN (-2375 2250) $PN BW13
J 0
(-2365 2260);
DISPLAY 0.617021 (-2365 2260);
PAINT ORANGE (-2365 2260);
FORCEPROP 2 LASTPIN (-2375 1300) $PN BK4
J 0
(-2365 1310);
DISPLAY 0.617021 (-2365 1310);
PAINT ORANGE (-2365 1310);
FORCEPROP 2 LASTPIN (-2375 2200) $PN BY14
J 0
(-2365 2210);
DISPLAY 0.617021 (-2365 2210);
PAINT ORANGE (-2365 2210);
FORCEPROP 2 LASTPIN (-2375 2150) $PN BY10
J 0
(-2365 2160);
DISPLAY 0.617021 (-2365 2160);
PAINT ORANGE (-2365 2160);
FORCEPROP 2 LASTPIN (-2375 2100) $PN CA11
J 0
(-2365 2110);
DISPLAY 0.617021 (-2365 2110);
PAINT ORANGE (-2365 2110);
FORCEPROP 2 LASTPIN (-2375 2050) $PN BV10
J 0
(-2365 2060);
DISPLAY 0.617021 (-2365 2060);
PAINT ORANGE (-2365 2060);
FORCEPROP 2 LASTPIN (-2375 2000) $PN BW9
J 0
(-2365 2010);
DISPLAY 0.617021 (-2365 2010);
PAINT ORANGE (-2365 2010);
FORCEPROP 2 LASTPIN (-2375 1950) $PN BW6
J 0
(-2365 1960);
DISPLAY 0.617021 (-2365 1960);
PAINT ORANGE (-2365 1960);
FORCEPROP 2 LASTPIN (-2375 1900) $PN BW11
J 0
(-2365 1910);
DISPLAY 0.617021 (-2365 1910);
PAINT ORANGE (-2365 1910);
FORCEPROP 2 LASTPIN (-2375 1850) $PN BT5
J 0
(-2365 1860);
DISPLAY 0.617021 (-2365 1860);
PAINT ORANGE (-2365 1860);
FORCEPROP 2 LASTPIN (-2375 1800) $PN BV8
J 0
(-2365 1810);
DISPLAY 0.617021 (-2365 1810);
PAINT ORANGE (-2365 1810);
FORCEPROP 2 LASTPIN (-2375 1750) $PN BW5
J 0
(-2365 1760);
DISPLAY 0.617021 (-2365 1760);
PAINT ORANGE (-2365 1760);
FORCEPROP 2 LASTPIN (-2375 1250) $PN BL1
J 0
(-2365 1260);
DISPLAY 0.617021 (-2365 1260);
PAINT ORANGE (-2365 1260);
FORCEPROP 2 LASTPIN (-2375 2950) $PN BY21
J 0
(-2365 2960);
DISPLAY 0.617021 (-2365 2960);
PAINT ORANGE (-2365 2960);
FORCEPROP 2 LASTPIN (-2375 2900) $PN BW22
J 0
(-2365 2910);
DISPLAY 0.617021 (-2365 2910);
PAINT ORANGE (-2365 2910);
FORCEPROP 2 LASTPIN (-2375 2850) $PN CA24
J 0
(-2365 2860);
DISPLAY 0.617021 (-2365 2860);
PAINT ORANGE (-2365 2860);
FORCEPROP 2 LASTPIN (-2375 2800) $PN BV23
J 0
(-2365 2810);
DISPLAY 0.617021 (-2365 2810);
PAINT ORANGE (-2365 2810);
FORCEPROP 2 LASTPIN (-2375 2750) $PN BW24
J 0
(-2365 2760);
DISPLAY 0.617021 (-2365 2760);
PAINT ORANGE (-2365 2760);
FORCEPROP 2 LASTPIN (-2375 2700) $PN BW20
J 0
(-2365 2710);
DISPLAY 0.617021 (-2365 2710);
PAINT ORANGE (-2365 2710);
FORCEPROP 2 LASTPIN (-2375 2650) $PN BY23
J 0
(-2365 2660);
DISPLAY 0.617021 (-2365 2660);
PAINT ORANGE (-2365 2660);
FORCEPROP 2 LASTPIN (-2375 2600) $PN CA22
J 0
(-2365 2610);
DISPLAY 0.617021 (-2365 2610);
PAINT ORANGE (-2365 2610);
FORCEPROP 2 LASTPIN (-2375 2550) $PN BV21
J 0
(-2365 2560);
DISPLAY 0.617021 (-2365 2560);
PAINT ORANGE (-2365 2560);
FORCEPROP 2 LASTPIN (-2375 3000) $PN BV25
J 0
(-2365 3010);
DISPLAY 0.617021 (-2365 3010);
PAINT ORANGE (-2365 3010);
FORCEPROP 2 LASTPIN (-2375 2500) $PN CA20
J 0
(-2365 2510);
DISPLAY 0.617021 (-2365 2510);
PAINT ORANGE (-2365 2510);
FORCEPROP 2 LASTPIN (-2375 3550) $PN AR3
J 0
(-2365 3560);
DISPLAY 0.617021 (-2365 3560);
PAINT ORANGE (-2365 3560);
FORCEPROP 2 LASTPIN (-2375 3500) $PN AV1
J 0
(-2365 3510);
DISPLAY 0.617021 (-2365 3510);
PAINT ORANGE (-2365 3510);
FORCEPROP 2 LASTPIN (-2375 3450) $PN AW2
J 0
(-2365 3460);
DISPLAY 0.617021 (-2365 3460);
PAINT ORANGE (-2365 3460);
FORCEPROP 2 LASTPIN (-2375 3300) $PN AR1
J 0
(-2365 3310);
DISPLAY 0.617021 (-2365 3310);
PAINT ORANGE (-2365 3310);
FORCEPROP 2 LASTPIN (-2375 3250) $PN AV3
J 0
(-2365 3260);
DISPLAY 0.617021 (-2365 3260);
PAINT ORANGE (-2365 3260);
FORCEPROP 2 LASTPIN (-2375 4300) $PN BH4
J 0
(-2365 4310);
DISPLAY 0.617021 (-2365 4310);
PAINT ORANGE (-2365 4310);
FORCEPROP 2 LASTPIN (-2375 4250) $PN BH2
J 0
(-2365 4260);
DISPLAY 0.617021 (-2365 4260);
PAINT ORANGE (-2365 4260);
FORCEPROP 2 LASTPIN (-2375 4200) $PN BA2
J 0
(-2365 4210);
DISPLAY 0.617021 (-2365 4210);
PAINT ORANGE (-2365 4210);
FORCEPROP 2 LASTPIN (-2375 4150) $PN BF3
J 0
(-2365 4160);
DISPLAY 0.617021 (-2365 4160);
PAINT ORANGE (-2365 4160);
FORCEPROP 2 LASTPIN (-2375 3200) $PN AW4
J 0
(-2365 3210);
DISPLAY 0.617021 (-2365 3210);
PAINT ORANGE (-2365 3210);
FORCEPROP 2 LASTPIN (-2375 4100) $PN BD3
J 0
(-2365 4110);
DISPLAY 0.617021 (-2365 4110);
PAINT ORANGE (-2365 4110);
FORCEPROP 2 LASTPIN (-2375 4050) $PN BC4
J 0
(-2365 4060);
DISPLAY 0.617021 (-2365 4060);
PAINT ORANGE (-2365 4060);
FORCEPROP 2 LASTPIN (-2375 4000) $PN BE4
J 0
(-2365 4010);
DISPLAY 0.617021 (-2365 4010);
PAINT ORANGE (-2365 4010);
FORCEPROP 2 LASTPIN (-2375 3950) $PN BF1
J 0
(-2365 3960);
DISPLAY 0.617021 (-2365 3960);
PAINT ORANGE (-2365 3960);
FORCEPROP 2 LASTPIN (-2375 3900) $PN BB3
J 0
(-2365 3910);
DISPLAY 0.617021 (-2365 3910);
PAINT ORANGE (-2365 3910);
FORCEPROP 2 LASTPIN (-2375 3850) $PN BC2
J 0
(-2365 3860);
DISPLAY 0.617021 (-2365 3860);
PAINT ORANGE (-2365 3860);
FORCEPROP 2 LASTPIN (-2375 3800) $PN AY1
J 0
(-2365 3810);
DISPLAY 0.617021 (-2365 3810);
PAINT ORANGE (-2365 3810);
FORCEPROP 2 LASTPIN (-2375 3150) $PN AT4
J 0
(-2365 3160);
DISPLAY 0.617021 (-2365 3160);
PAINT ORANGE (-2365 3160);
FORCEPROP 2 LASTPIN (-5575 1650) $PN AV11
J 2
(-5585 1660);
DISPLAY 0.617021 (-5585 1660);
PAINT ORANGE (-5585 1660);
FORCEPROP 2 LASTPIN (-5575 1600) $PN BG11
J 2
(-5585 1610);
DISPLAY 0.617021 (-5585 1610);
PAINT ORANGE (-5585 1610);
FORCEPROP 2 LASTPIN (-5575 1550) $PN AY15
J 2
(-5585 1560);
DISPLAY 0.617021 (-5585 1560);
PAINT ORANGE (-5585 1560);
FORCEPROP 2 LASTPIN (-5575 1500) $PN AV18
J 2
(-5585 1510);
DISPLAY 0.617021 (-5585 1510);
PAINT ORANGE (-5585 1510);
FORCEPROP 2 LASTPIN (-5575 1450) $PN AW20
J 2
(-5585 1460);
DISPLAY 0.617021 (-5585 1460);
PAINT ORANGE (-5585 1460);
FORCEPROP 2 LASTPIN (-5575 1400) $PN BA9
J 2
(-5585 1410);
DISPLAY 0.617021 (-5585 1410);
PAINT ORANGE (-5585 1410);
FORCEPROP 2 LASTPIN (-5575 1350) $PN AY7
J 2
(-5585 1360);
DISPLAY 0.617021 (-5585 1360);
PAINT ORANGE (-5585 1360);
FORCEPROP 2 LASTPIN (-5575 1300) $PN BE22
J 2
(-5585 1310);
DISPLAY 0.617021 (-5585 1310);
PAINT ORANGE (-5585 1310);
FORCEPROP 2 LASTPIN (-5575 2350) $PN BA13
J 2
(-5585 2360);
DISPLAY 0.617021 (-5585 2360);
PAINT ORANGE (-5585 2360);
FORCEPROP 2 LASTPIN (-5575 2300) $PN BD20
J 2
(-5585 2310);
DISPLAY 0.617021 (-5585 2310);
PAINT ORANGE (-5585 2310);
FORCEPROP 2 LASTPIN (-5575 2250) $PN BG7
J 2
(-5585 2260);
DISPLAY 0.617021 (-5585 2260);
PAINT ORANGE (-5585 2260);
FORCEPROP 2 LASTPIN (-5575 2200) $PN BA17
J 2
(-5585 2210);
DISPLAY 0.617021 (-5585 2210);
PAINT ORANGE (-5585 2210);
FORCEPROP 2 LASTPIN (-5575 1250) $PN AV15
J 2
(-5585 1260);
DISPLAY 0.617021 (-5585 1260);
PAINT ORANGE (-5585 1260);
FORCEPROP 2 LASTPIN (-5575 2150) $PN BE15
J 2
(-5585 2160);
DISPLAY 0.617021 (-5585 2160);
PAINT ORANGE (-5585 2160);
FORCEPROP 2 LASTPIN (-5575 2100) $PN BE7
J 2
(-5585 2110);
DISPLAY 0.617021 (-5585 2110);
PAINT ORANGE (-5585 2110);
FORCEPROP 2 LASTPIN (-5575 2050) $PN BD9
J 2
(-5585 2060);
DISPLAY 0.617021 (-5585 2060);
PAINT ORANGE (-5585 2060);
FORCEPROP 2 LASTPIN (-5575 2000) $PN BD17
J 2
(-5585 2010);
DISPLAY 0.617021 (-5585 2010);
PAINT ORANGE (-5585 2010);
FORCEPROP 2 LASTPIN (-5575 1950) $PN BE18
J 2
(-5585 1960);
DISPLAY 0.617021 (-5585 1960);
PAINT ORANGE (-5585 1960);
FORCEPROP 2 LASTPIN (-5575 1900) $PN AV7
J 2
(-5585 1910);
DISPLAY 0.617021 (-5585 1910);
PAINT ORANGE (-5585 1910);
FORCEPROP 2 LASTPIN (-5575 1850) $PN AY18
J 2
(-5585 1860);
DISPLAY 0.617021 (-5585 1860);
PAINT ORANGE (-5585 1860);
FORCEPROP 2 LASTPIN (-5575 1800) $PN BD13
J 2
(-5585 1810);
DISPLAY 0.617021 (-5585 1810);
PAINT ORANGE (-5585 1810);
FORCEPROP 2 LASTPIN (-5575 1750) $PN BA20
J 2
(-5585 1760);
DISPLAY 0.617021 (-5585 1760);
PAINT ORANGE (-5585 1760);
FORCEPROP 2 LASTPIN (-5575 1700) $PN BE11
J 2
(-5585 1710);
DISPLAY 0.617021 (-5585 1710);
PAINT ORANGE (-5585 1710);
FORCEPROP 2 LASTPIN (-5575 1200) $PN AY11
J 2
(-5585 1210);
DISPLAY 0.617021 (-5585 1210);
PAINT ORANGE (-5585 1210);
FORCEPROP 2 LASTPIN (-5575 2900) $PN AR20
J 2
(-5585 2910);
DISPLAY 0.617021 (-5585 2910);
PAINT ORANGE (-5585 2910);
FORCEPROP 2 LASTPIN (-5575 2850) $PN AH9
J 2
(-5585 2860);
DISPLAY 0.617021 (-5585 2860);
PAINT ORANGE (-5585 2860);
FORCEPROP 2 LASTPIN (-5575 2800) $PN AK17
J 2
(-5585 2810);
DISPLAY 0.617021 (-5585 2810);
PAINT ORANGE (-5585 2810);
FORCEPROP 2 LASTPIN (-5575 2750) $PN AL18
J 2
(-5585 2760);
DISPLAY 0.617021 (-5585 2760);
PAINT ORANGE (-5585 2760);
FORCEPROP 2 LASTPIN (-5575 2700) $PN AH17
J 2
(-5585 2710);
DISPLAY 0.617021 (-5585 2710);
PAINT ORANGE (-5585 2710);
FORCEPROP 2 LASTPIN (-5575 2650) $PN AH13
J 2
(-5585 2660);
DISPLAY 0.617021 (-5585 2660);
PAINT ORANGE (-5585 2660);
FORCEPROP 2 LASTPIN (-5575 2600) $PN AK13
J 2
(-5585 2610);
DISPLAY 0.617021 (-5585 2610);
PAINT ORANGE (-5585 2610);
FORCEPROP 2 LASTPIN (-5575 2550) $PN AK20
J 2
(-5585 2560);
DISPLAY 0.617021 (-5585 2560);
PAINT ORANGE (-5585 2560);
FORCEPROP 2 LASTPIN (-5575 3600) $PN AU17
J 2
(-5585 3610);
DISPLAY 0.617021 (-5585 3610);
PAINT ORANGE (-5585 3610);
FORCEPROP 2 LASTPIN (-5575 3550) $PN AP18
J 2
(-5585 3560);
DISPLAY 0.617021 (-5585 3560);
PAINT ORANGE (-5585 3560);
FORCEPROP 2 LASTPIN (-5575 3500) $PN AR17
J 2
(-5585 3510);
DISPLAY 0.617021 (-5585 3510);
PAINT ORANGE (-5585 3510);
FORCEPROP 2 LASTPIN (-5575 3450) $PN AU20
J 2
(-5585 3460);
DISPLAY 0.617021 (-5585 3460);
PAINT ORANGE (-5585 3460);
FORCEPROP 2 LASTPIN (-5575 2500) $PN AK9
J 2
(-5585 2510);
DISPLAY 0.617021 (-5585 2510);
PAINT ORANGE (-5585 2510);
FORCEPROP 2 LASTPIN (-5575 3400) $PN AU9
J 2
(-5585 3410);
DISPLAY 0.617021 (-5585 3410);
PAINT ORANGE (-5585 3410);
FORCEPROP 2 LASTPIN (-5575 3350) $PN AL15
J 2
(-5585 3360);
DISPLAY 0.617021 (-5585 3360);
PAINT ORANGE (-5585 3360);
FORCEPROP 2 LASTPIN (-5575 3300) $PN AP15
J 2
(-5585 3310);
DISPLAY 0.617021 (-5585 3310);
PAINT ORANGE (-5585 3310);
FORCEPROP 2 LASTPIN (-5575 3250) $PN AU13
J 2
(-5585 3260);
DISPLAY 0.617021 (-5585 3260);
PAINT ORANGE (-5585 3260);
FORCEPROP 2 LASTPIN (-5575 3200) $PN AR13
J 2
(-5585 3210);
DISPLAY 0.617021 (-5585 3210);
PAINT ORANGE (-5585 3210);
FORCEPROP 2 LASTPIN (-5575 3150) $PN AL11
J 2
(-5585 3160);
DISPLAY 0.617021 (-5585 3160);
PAINT ORANGE (-5585 3160);
FORCEPROP 2 LASTPIN (-5575 3100) $PN AP11
J 2
(-5585 3110);
DISPLAY 0.617021 (-5585 3110);
PAINT ORANGE (-5585 3110);
FORCEPROP 2 LASTPIN (-5575 3050) $PN AP7
J 2
(-5585 3060);
DISPLAY 0.617021 (-5585 3060);
PAINT ORANGE (-5585 3060);
FORCEPROP 2 LASTPIN (-5575 3000) $PN AR9
J 2
(-5585 3010);
DISPLAY 0.617021 (-5585 3010);
PAINT ORANGE (-5585 3010);
FORCEPROP 2 LASTPIN (-5575 2950) $PN AL7
J 2
(-5585 2960);
DISPLAY 0.617021 (-5585 2960);
PAINT ORANGE (-5585 2960);
FORCEPROP 2 LASTPIN (-5575 2450) $PN AG7
J 2
(-5585 2460);
DISPLAY 0.617021 (-5585 2460);
PAINT ORANGE (-5585 2460);
FORCEPROP 2 LASTPIN (-5575 4150) $PN BL48
J 2
(-5585 4160);
DISPLAY 0.617021 (-5585 4160);
PAINT ORANGE (-5585 4160);
FORCEPROP 2 LASTPIN (-5575 4100) $PN AV56
J 2
(-5585 4110);
DISPLAY 0.617021 (-5585 4110);
PAINT ORANGE (-5585 4110);
FORCEPROP 2 LASTPIN (-5575 4050) $PN BJ48
J 2
(-5585 4060);
DISPLAY 0.617021 (-5585 4060);
PAINT ORANGE (-5585 4060);
FORCEPROP 2 LASTPIN (-5575 4000) $PN BB52
J 2
(-5585 4010);
DISPLAY 0.617021 (-5585 4010);
PAINT ORANGE (-5585 4010);
FORCEPROP 2 LASTPIN (-5575 3950) $PN AT52
J 2
(-5585 3960);
DISPLAY 0.617021 (-5585 3960);
PAINT ORANGE (-5585 3960);
FORCEPROP 2 LASTPIN (-5575 3900) $PN AV52
J 2
(-5585 3910);
DISPLAY 0.617021 (-5585 3910);
PAINT ORANGE (-5585 3910);
FORCEPROP 2 LASTPIN (-5575 3850) $PN BE52
J 2
(-5585 3860);
DISPLAY 0.617021 (-5585 3860);
PAINT ORANGE (-5585 3860);
FORCEPROP 2 LASTPIN (-5575 3800) $PN BG52
J 2
(-5585 3810);
DISPLAY 0.617021 (-5585 3810);
PAINT ORANGE (-5585 3810);
FORCEPROP 2 LASTPIN (-5575 3750) $PN AY52
J 2
(-5585 3760);
DISPLAY 0.617021 (-5585 3760);
PAINT ORANGE (-5585 3760);
FORCEPROP 2 LASTPIN (-5575 4300) $PN AU58
J 2
(-5585 4310);
DISPLAY 0.617021 (-5585 4310);
PAINT ORANGE (-5585 4310);
FORCEPROP 2 LASTPIN (-5575 4250) $PN AW54
J 2
(-5585 4260);
DISPLAY 0.617021 (-5585 4260);
PAINT ORANGE (-5585 4260);
FORCEPROP 2 LASTPIN (-5575 4200) $PN BN48
J 2
(-5585 4210);
DISPLAY 0.617021 (-5585 4210);
PAINT ORANGE (-5585 4210);
FORCEPROP 2 LASTPIN (-5575 3700) $PN BH50
J 2
(-5585 3710);
DISPLAY 0.617021 (-5585 3710);
PAINT ORANGE (-5585 3710);
FORCEPROP 2 LASTPIN (-2375 3050) $PN BY25
J 0
(-2365 3060);
DISPLAY 0.617021 (-2365 3060);
PAINT ORANGE (-2365 3060);
FORCEPROP 2 LASTPIN (-2375 3350) $PN AT2
J 0
(-2365 3360);
DISPLAY 0.617021 (-2365 3360);
PAINT ORANGE (-2365 3360);
FORCEPROP 2 LASTPIN (-2375 3400) $PN AY3
J 0
(-2365 3410);
DISPLAY 0.617021 (-2365 3410);
PAINT ORANGE (-2365 3410);
FORCEPROP 2 LASTPIN (-2375 3750) $PN BB1
J 0
(-2365 3760);
DISPLAY 0.617021 (-2365 3760);
PAINT ORANGE (-2365 3760);
FORCEPROP 2 LASTPIN (-2375 3650) $PN BA4
J 0
(-2365 3660);
DISPLAY 0.617021 (-2365 3660);
PAINT ORANGE (-2365 3660);
FORCEPROP 2 LASTPIN (-2375 3600) $PN BE2
J 0
(-2365 3610);
DISPLAY 0.617021 (-2365 3610);
PAINT ORANGE (-2365 3610);
FORCEPROP 2 LASTPIN (-2375 3700) $PN BD1
J 0
(-2365 3710);
DISPLAY 0.617021 (-2365 3710);
PAINT ORANGE (-2365 3710);
FORCEPROP 1 LAST MATERIAL IC
J 0
(-5525 4500);
DISPLAY 0.617021 (-5525 4500);
PAINT SKYBLUE (-5525 4500);
FORCEPROP 1 LAST PART_NUMBER H91415-002
J 0
(-5525 1000);
DISPLAY 0.617021 (-5525 1000);
PAINT BLUE (-5525 1000);
FORCEPROP 1 LAST LOCATION U7C1
J 0
(-5525 4550);
DISPLAY 0.617021 (-5525 4550);
PAINT AQUA (-5525 4550);
FORCEPROP 1 LAST PATH I147
J 0
(-3975 4500);
PAINT GREEN (-3975 4500);
DISPLAY INVISIBLE (-3975 4500);
FORCEPROP 2 LAST CDS_LOCATION U7C1
J 0
(-5525 4550);
DISPLAY 0.617021 (-5525 4550);
PAINT AQUA (-5525 4550);
DISPLAY INVISIBLE (-5525 4550);
FORCEPROP 0 LAST BOM_COST SB
J 0
(-4425 4950);
DISPLAY 1.361702 (-4425 4950);
PAINT ORANGE (-4425 4950);
DISPLAY INVISIBLE (-4425 4950);
FORCEPROP 2 LAST CDS_LIB mstr_u_proc
J 0
(-3975 2800);
PAINT ORANGE (-3975 2800);
DISPLAY INVISIBLE (-3975 2800);
FORCEPROP 2 LAST SEC 7
J 0
(-5525 4600);
DISPLAY 0.680851 (-5525 4600);
PAINT MONO (-5525 4600);
DISPLAY INVISIBLE (-5525 4600);
FORCEPROP 2 LAST SEC_TYPE BGA1
J 0
(-5525 4600);
DISPLAY 1.021277 (-5525 4600);
PAINT ORANGE (-5525 4600);
DISPLAY INVISIBLE (-5525 4600);
FORCEPROP 0 LAST ROOM SB
J 0
(-4425 4850);
DISPLAY 1.361702 (-4425 4850);
PAINT ORANGE (-4425 4850);
DISPLAY INVISIBLE (-4425 4850);
FORCEPROP 1 LAST PACK_TYPE BGA1
J 0
(-5525 4600);
PAINT SKYBLUE (-5525 4600);
DISPLAY INVISIBLE (-5525 4600);
FORCEADD RES..2
(-775 2825);
FORCEPROP 1 LASTPIN (-775 2925) $PN 1
J 0
(-770 2887);
DISPLAY 0.617021 (-770 2887);
PAINT ORANGE (-770 2887);
FORCEPROP 1 LASTPIN (-775 2725) $PN 2
J 0
(-770 2735);
DISPLAY 0.617021 (-770 2735);
PAINT ORANGE (-770 2735);
FORCEPROP 1 LAST WATTAGE 1/16W
J 0
(-735 2800);
DISPLAY 0.617021 (-735 2800);
PAINT SKYBLUE (-735 2800);
FORCEPROP 1 LAST MATERIAL CHIP
J 0
(-735 2750);
DISPLAY 0.617021 (-735 2750);
PAINT SKYBLUE (-735 2750);
FORCEPROP 1 LAST PACK_TYPE 0402
J 0
(-735 2650);
DISPLAY 0.617021 (-735 2650);
PAINT SKYBLUE (-735 2650);
FORCEPROP 1 LAST TOLERANCE 1%
J 0
(-730 2850);
DISPLAY 0.617021 (-730 2850);
PAINT SKYBLUE (-730 2850);
FORCEPROP 1 LAST VALUE 100.0
J 0
(-730 2900);
DISPLAY 0.617021 (-730 2900);
PAINT SKYBLUE (-730 2900);
FORCEPROP 1 LAST PART_NUMBER G21796-017
J 0
(-735 2700);
DISPLAY 0.617021 (-735 2700);
PAINT BLUE (-735 2700);
FORCEPROP 1 LAST LOCATION R8C21
J 0
(-730 2950);
DISPLAY 0.617021 (-730 2950);
PAINT AQUA (-730 2950);
FORCEPROP 2 LAST CDS_LIB mstr_discrete
J 0
(-775 2825);
PAINT ORANGE (-775 2825);
DISPLAY INVISIBLE (-775 2825);
FORCEPROP 2 LAST CDS_LOCATION R8C21
J 0
(-825 2875);
DISPLAY 0.617021 (-825 2875);
PAINT AQUA (-825 2875);
DISPLAY INVISIBLE (-825 2875);
FORCEPROP 1 LAST PATH I148
J 0
(-725 3000);
DISPLAY 0.978723 (-725 3000);
PAINT WHITE (-725 3000);
DISPLAY INVISIBLE (-725 3000);
FORCEPROP 2 LAST SEC_TYPE 0402
J 0
(-725 3050);
DISPLAY 1.021277 (-725 3050);
PAINT ORANGE (-725 3050);
DISPLAY INVISIBLE (-725 3050);
FORCEPROP 2 LAST SEC 1
J 0
(-725 3050);
DISPLAY 0.680851 (-725 3050);
PAINT MONO (-725 3050);
DISPLAY INVISIBLE (-725 3050);
FORCEPROP 0 LAST ROOM SB
J 0
(-825 3025);
DISPLAY 1.021277 (-825 3025);
PAINT ORANGE (-825 3025);
DISPLAY INVISIBLE (-825 3025);
FORCEADD OFFPAGE..5
R 2
(-1550 3650);
FORCEPROP 2 LAST $XR0 138 
J 0
(-1361 3650);
DISPLAY 0.638298 (-1361 3650);
PAINT MONO (-1361 3650);
FORCEPROP 2 LAST CDS_LIB mstr_standard
J 2
(-1550 3650);
DISPLAY 1.212766 (-1550 3650);
PAINT ORANGE (-1550 3650);
DISPLAY INVISIBLE (-1550 3650);
FORCEPROP 1 LAST OFFPAGE TRUE
J 2
(-1875 3525);
DISPLAY 0.872340 (-1875 3525);
PAINT GREEN (-1875 3525);
DISPLAY INVISIBLE (-1875 3525);
FORCEPROP 1 LAST COMMENT_BODY TRUE
J 2
(-1650 3575);
DISPLAY 0.872340 (-1650 3575);
PAINT GREEN (-1650 3575);
DISPLAY INVISIBLE (-1650 3575);
FORCEPROP 2 LAST PATH I15
J 0
(-1350 3725);
DISPLAY 1.021277 (-1350 3725);
PAINT ORANGE (-1350 3725);
DISPLAY INVISIBLE (-1350 3725);
FORCEADD OFFPAGE..1
(-7200 4150);
FORCEPROP 2 LAST $XR0 176 
J 0
(-7482 4150);
DISPLAY 0.638298 (-7482 4150);
PAINT MONO (-7482 4150);
FORCEPROP 2 LAST CDS_LIB mstr_standard
J 0
(-7200 4150);
DISPLAY 1.212766 (-7200 4150);
PAINT ORANGE (-7200 4150);
DISPLAY INVISIBLE (-7200 4150);
FORCEPROP 1 LAST OFFPAGE TRUE
J 0
(-6875 4025);
PAINT GREEN (-6875 4025);
DISPLAY INVISIBLE (-6875 4025);
FORCEPROP 1 LAST COMMENT_BODY TRUE
J 0
(-7075 4050);
DISPLAY 1.404255 (-7075 4050);
PAINT PEACH (-7075 4050);
DISPLAY INVISIBLE (-7075 4050);
FORCEPROP 2 LAST PATH I150
J 0
(-7475 4200);
DISPLAY 1.021277 (-7475 4200);
PAINT ORANGE (-7475 4200);
DISPLAY INVISIBLE (-7475 4200);
FORCEADD OFFPAGE..4
(-1550 2850);
FORCEPROP 2 LAST $XR0 189 
J 0
(-1364 2850);
DISPLAY 0.638298 (-1364 2850);
PAINT MONO (-1364 2850);
FORCEPROP 2 LAST CDS_LIB mstr_standard
J 0
(-1550 2850);
PAINT ORANGE (-1550 2850);
DISPLAY INVISIBLE (-1550 2850);
FORCEPROP 1 LAST OFFPAGE TRUE
J 0
(-1225 2725);
DISPLAY 0.872340 (-1225 2725);
PAINT GREEN (-1225 2725);
DISPLAY INVISIBLE (-1225 2725);
FORCEPROP 1 LAST COMMENT_BODY TRUE
J 0
(-1575 2750);
DISPLAY 0.872340 (-1575 2750);
PAINT GREEN (-1575 2750);
DISPLAY INVISIBLE (-1575 2750);
FORCEPROP 2 LAST PATH I151
J 0
(-1375 2925);
DISPLAY 1.021277 (-1375 2925);
PAINT ORANGE (-1375 2925);
DISPLAY INVISIBLE (-1375 2925);
FORCEADD OFFPAGE..1
(-7200 4050);
FORCEPROP 2 LAST $XR0 89 
J 0
(-7451 4050);
DISPLAY 0.638298 (-7451 4050);
PAINT MONO (-7451 4050);
FORCEPROP 2 LAST $XR1 156 
J 0
(-7571 4050);
DISPLAY 0.638298 (-7571 4050);
PAINT MONO (-7571 4050);
FORCEPROP 2 LAST $XR2 157 
J 0
(-7691 4050);
DISPLAY 0.638298 (-7691 4050);
PAINT MONO (-7691 4050);
FORCEPROP 2 LAST $XR3 191 
J 0
(-7811 4050);
DISPLAY 0.638298 (-7811 4050);
PAINT MONO (-7811 4050);
FORCEPROP 2 LAST CDS_LIB mstr_standard
J 0
(-7200 4050);
PAINT ORANGE (-7200 4050);
DISPLAY INVISIBLE (-7200 4050);
FORCEPROP 1 LAST OFFPAGE TRUE
J 0
(-6875 3925);
PAINT GREEN (-6875 3925);
DISPLAY INVISIBLE (-6875 3925);
FORCEPROP 1 LAST COMMENT_BODY TRUE
J 0
(-7075 3950);
DISPLAY 1.404255 (-7075 3950);
PAINT PEACH (-7075 3950);
DISPLAY INVISIBLE (-7075 3950);
FORCEPROP 2 LAST PATH I152
J 0
(-7150 4125);
DISPLAY 1.021277 (-7150 4125);
PAINT ORANGE (-7150 4125);
DISPLAY INVISIBLE (-7150 4125);
FORCEADD OFFPAGE..1
(-7200 3900);
FORCEPROP 2 LAST $XR0 92 
J 0
(-7421 3900);
DISPLAY 0.638298 (-7421 3900);
PAINT MONO (-7421 3900);
FORCEPROP 2 LAST $XR1 144 
J 0
(-7541 3900);
DISPLAY 0.638298 (-7541 3900);
PAINT MONO (-7541 3900);
FORCEPROP 2 LAST CDS_LIB mstr_standard
J 0
(-7200 3900);
PAINT MONO (-7200 3900);
DISPLAY INVISIBLE (-7200 3900);
FORCEPROP 1 LAST OFFPAGE TRUE
J 0
(-6875 3775);
DISPLAY 0.872340 (-6875 3775);
PAINT GREEN (-6875 3775);
DISPLAY INVISIBLE (-6875 3775);
FORCEPROP 1 LAST COMMENT_BODY TRUE
J 0
(-7075 3800);
DISPLAY 0.872340 (-7075 3800);
PAINT GREEN (-7075 3800);
DISPLAY INVISIBLE (-7075 3800);
FORCEPROP 2 LAST PATH I154
J 0
(-7150 3975);
DISPLAY 1.021277 (-7150 3975);
PAINT ORANGE (-7150 3975);
DISPLAY INVISIBLE (-7150 3975);
FORCEADD OFFPAGE..5
(-7200 4200);
FORCEPROP 2 LAST $XR0 133 
J 0
(-7485 4200);
DISPLAY 0.638298 (-7485 4200);
PAINT MONO (-7485 4200);
FORCEPROP 2 LAST $XR1 146 
J 0
(-7605 4200);
DISPLAY 0.638298 (-7605 4200);
PAINT MONO (-7605 4200);
FORCEPROP 2 LAST $XR2 119 
J 0
(-7725 4200);
DISPLAY 0.638298 (-7725 4200);
PAINT MONO (-7725 4200);
FORCEPROP 2 LAST CDS_LIB mstr_standard
J 0
(-7200 4200);
PAINT MONO (-7200 4200);
DISPLAY INVISIBLE (-7200 4200);
FORCEPROP 1 LAST OFFPAGE TRUE
J 0
(-6875 4075);
PAINT GREEN (-6875 4075);
DISPLAY INVISIBLE (-6875 4075);
FORCEPROP 1 LAST COMMENT_BODY TRUE
J 0
(-7100 4125);
DISPLAY 1.404255 (-7100 4125);
PAINT PEACH (-7100 4125);
DISPLAY INVISIBLE (-7100 4125);
FORCEPROP 2 LAST PATH I155
J 0
(-7150 4275);
DISPLAY 1.021277 (-7150 4275);
PAINT ORANGE (-7150 4275);
DISPLAY INVISIBLE (-7150 4275);
FORCEADD OFFPAGE..5
(-7200 4250);
FORCEPROP 2 LAST $XR0 133 
J 0
(-7485 4250);
DISPLAY 0.638298 (-7485 4250);
PAINT MONO (-7485 4250);
FORCEPROP 2 LAST $XR1 144 
J 0
(-7605 4250);
DISPLAY 0.638298 (-7605 4250);
PAINT MONO (-7605 4250);
FORCEPROP 2 LAST $XR2 119 
J 0
(-7725 4250);
DISPLAY 0.638298 (-7725 4250);
PAINT MONO (-7725 4250);
FORCEPROP 2 LAST CDS_LIB mstr_standard
J 0
(-7200 4250);
PAINT MONO (-7200 4250);
DISPLAY INVISIBLE (-7200 4250);
FORCEPROP 1 LAST OFFPAGE TRUE
J 0
(-6875 4125);
PAINT GREEN (-6875 4125);
DISPLAY INVISIBLE (-6875 4125);
FORCEPROP 1 LAST COMMENT_BODY TRUE
J 0
(-7100 4175);
DISPLAY 1.404255 (-7100 4175);
PAINT PEACH (-7100 4175);
DISPLAY INVISIBLE (-7100 4175);
FORCEPROP 2 LAST PATH I156
J 0
(-7150 4325);
DISPLAY 1.021277 (-7150 4325);
PAINT ORANGE (-7150 4325);
DISPLAY INVISIBLE (-7150 4325);
FORCEADD OFFPAGE..1
(-7200 4300);
FORCEPROP 2 LAST $XR0 200 
J 0
(-7452 4300);
DISPLAY 0.638298 (-7452 4300);
PAINT MONO (-7452 4300);
FORCEPROP 2 LAST $XR1 145 
J 0
(-7572 4300);
DISPLAY 0.638298 (-7572 4300);
PAINT MONO (-7572 4300);
FORCEPROP 2 LAST $XR2 170 
J 0
(-7692 4300);
DISPLAY 0.638298 (-7692 4300);
PAINT MONO (-7692 4300);
FORCEPROP 2 LAST CDS_LIB mstr_standard
J 0
(-7200 4300);
PAINT MONO (-7200 4300);
DISPLAY INVISIBLE (-7200 4300);
FORCEPROP 1 LAST OFFPAGE TRUE
J 0
(-6875 4175);
PAINT GREEN (-6875 4175);
DISPLAY INVISIBLE (-6875 4175);
FORCEPROP 1 LAST COMMENT_BODY TRUE
J 0
(-7075 4200);
DISPLAY 1.404255 (-7075 4200);
PAINT PEACH (-7075 4200);
DISPLAY INVISIBLE (-7075 4200);
FORCEPROP 2 LAST PATH I157
J 0
(-7150 4375);
DISPLAY 1.021277 (-7150 4375);
PAINT ORANGE (-7150 4375);
DISPLAY INVISIBLE (-7150 4375);
FORCEADD OFFPAGE..1
(-7200 2450);
FORCEPROP 2 LAST $XR0 200 
J 0
(-7452 2450);
DISPLAY 0.638298 (-7452 2450);
PAINT MONO (-7452 2450);
FORCEPROP 2 LAST $XR1 145 
J 0
(-7572 2450);
DISPLAY 0.638298 (-7572 2450);
PAINT MONO (-7572 2450);
FORCEPROP 2 LAST CDS_LIB mstr_standard
J 0
(-7200 2450);
PAINT MONO (-7200 2450);
DISPLAY INVISIBLE (-7200 2450);
FORCEPROP 1 LAST OFFPAGE TRUE
J 0
(-6875 2325);
PAINT GREEN (-6875 2325);
DISPLAY INVISIBLE (-6875 2325);
FORCEPROP 1 LAST COMMENT_BODY TRUE
J 0
(-7075 2350);
DISPLAY 1.404255 (-7075 2350);
PAINT PEACH (-7075 2350);
DISPLAY INVISIBLE (-7075 2350);
FORCEPROP 2 LAST PATH I158
J 0
(-7150 2525);
DISPLAY 1.021277 (-7150 2525);
PAINT ORANGE (-7150 2525);
DISPLAY INVISIBLE (-7150 2525);
FORCEADD OFFPAGE..1
(-7200 2500);
FORCEPROP 2 LAST $XR0 200 
J 0
(-7452 2500);
DISPLAY 0.638298 (-7452 2500);
PAINT MONO (-7452 2500);
FORCEPROP 2 LAST $XR1 145 
J 0
(-7572 2500);
DISPLAY 0.638298 (-7572 2500);
PAINT MONO (-7572 2500);
FORCEPROP 2 LAST $XR2 170 
J 0
(-7692 2500);
DISPLAY 0.638298 (-7692 2500);
PAINT MONO (-7692 2500);
FORCEPROP 2 LAST CDS_LIB mstr_standard
J 0
(-7200 2500);
PAINT MONO (-7200 2500);
DISPLAY INVISIBLE (-7200 2500);
FORCEPROP 1 LAST OFFPAGE TRUE
J 0
(-6875 2375);
PAINT GREEN (-6875 2375);
DISPLAY INVISIBLE (-6875 2375);
FORCEPROP 1 LAST COMMENT_BODY TRUE
J 0
(-7075 2400);
DISPLAY 1.404255 (-7075 2400);
PAINT PEACH (-7075 2400);
DISPLAY INVISIBLE (-7075 2400);
FORCEPROP 2 LAST PATH I159
J 0
(-7150 2575);
DISPLAY 1.021277 (-7150 2575);
PAINT ORANGE (-7150 2575);
DISPLAY INVISIBLE (-7150 2575);
FORCEADD OFFPAGE..5
R 2
(-1550 3200);
FORCEPROP 2 LAST $XR0 147 
J 0
(-1361 3200);
DISPLAY 0.638298 (-1361 3200);
PAINT MONO (-1361 3200);
FORCEPROP 2 LAST $XR1 154 
J 0
(-1241 3200);
DISPLAY 0.638298 (-1241 3200);
PAINT MONO (-1241 3200);
FORCEPROP 2 LAST CDS_LIB mstr_standard
J 2
(-1550 3200);
DISPLAY 1.212766 (-1550 3200);
PAINT ORANGE (-1550 3200);
DISPLAY INVISIBLE (-1550 3200);
FORCEPROP 1 LAST OFFPAGE TRUE
J 2
(-1875 3075);
DISPLAY 0.872340 (-1875 3075);
PAINT GREEN (-1875 3075);
DISPLAY INVISIBLE (-1875 3075);
FORCEPROP 1 LAST COMMENT_BODY TRUE
J 2
(-1650 3125);
DISPLAY 0.872340 (-1650 3125);
PAINT GREEN (-1650 3125);
DISPLAY INVISIBLE (-1650 3125);
FORCEPROP 2 LAST PATH I16
J 0
(-1375 3275);
DISPLAY 1.021277 (-1375 3275);
PAINT ORANGE (-1375 3275);
DISPLAY INVISIBLE (-1375 3275);
FORCEADD OFFPAGE..1
(-7200 2550);
FORCEPROP 2 LAST $XR0 157 
J 0
(-7452 2550);
DISPLAY 0.638298 (-7452 2550);
PAINT MONO (-7452 2550);
FORCEPROP 2 LAST $XR1 181 
J 0
(-7572 2550);
DISPLAY 0.638298 (-7572 2550);
PAINT MONO (-7572 2550);
FORCEPROP 2 LAST $XR2 144 
J 0
(-7692 2550);
DISPLAY 0.638298 (-7692 2550);
PAINT MONO (-7692 2550);
FORCEPROP 2 LAST $XR3 190 
J 0
(-7812 2550);
DISPLAY 0.638298 (-7812 2550);
PAINT MONO (-7812 2550);
FORCEPROP 2 LAST CDS_LIB mstr_standard
J 0
(-7200 2550);
PAINT MONO (-7200 2550);
DISPLAY INVISIBLE (-7200 2550);
FORCEPROP 1 LAST OFFPAGE TRUE
J 0
(-6875 2425);
PAINT GREEN (-6875 2425);
DISPLAY INVISIBLE (-6875 2425);
FORCEPROP 1 LAST COMMENT_BODY TRUE
J 0
(-7075 2450);
DISPLAY 1.404255 (-7075 2450);
PAINT PEACH (-7075 2450);
DISPLAY INVISIBLE (-7075 2450);
FORCEPROP 2 LAST PATH I160
J 0
(-7150 2625);
DISPLAY 1.021277 (-7150 2625);
PAINT ORANGE (-7150 2625);
DISPLAY INVISIBLE (-7150 2625);
FORCEADD OFFPAGE..1
(-7200 2600);
FORCEPROP 2 LAST $XR0 147 
J 0
(-7482 2600);
DISPLAY 0.638298 (-7482 2600);
PAINT MONO (-7482 2600);
FORCEPROP 2 LAST $XR1 157 
J 0
(-7602 2600);
DISPLAY 0.638298 (-7602 2600);
PAINT MONO (-7602 2600);
FORCEPROP 2 LAST $XR2 181 
J 0
(-7722 2600);
DISPLAY 0.638298 (-7722 2600);
PAINT MONO (-7722 2600);
FORCEPROP 2 LAST CDS_LIB mstr_standard
J 0
(-7200 2600);
PAINT MONO (-7200 2600);
DISPLAY INVISIBLE (-7200 2600);
FORCEPROP 1 LAST OFFPAGE TRUE
J 0
(-6875 2475);
PAINT GREEN (-6875 2475);
DISPLAY INVISIBLE (-6875 2475);
FORCEPROP 1 LAST COMMENT_BODY TRUE
J 0
(-7075 2500);
DISPLAY 1.404255 (-7075 2500);
PAINT PEACH (-7075 2500);
DISPLAY INVISIBLE (-7075 2500);
FORCEPROP 2 LAST PATH I161
J 0
(-7150 2675);
DISPLAY 1.021277 (-7150 2675);
PAINT ORANGE (-7150 2675);
DISPLAY INVISIBLE (-7150 2675);
FORCEADD OFFPAGE..1
(-7200 3350);
FORCEPROP 2 LAST $XR0 191 
J 0
(-7482 3350);
DISPLAY 0.638298 (-7482 3350);
PAINT MONO (-7482 3350);
FORCEPROP 2 LAST $XR1 145 
J 0
(-7602 3350);
DISPLAY 0.638298 (-7602 3350);
PAINT MONO (-7602 3350);
FORCEPROP 2 LAST CDS_LIB mstr_standard
J 0
(-7200 3350);
PAINT MONO (-7200 3350);
DISPLAY INVISIBLE (-7200 3350);
FORCEPROP 1 LAST OFFPAGE TRUE
J 0
(-6875 3225);
PAINT GREEN (-6875 3225);
DISPLAY INVISIBLE (-6875 3225);
FORCEPROP 1 LAST COMMENT_BODY TRUE
J 0
(-7075 3250);
DISPLAY 1.404255 (-7075 3250);
PAINT PEACH (-7075 3250);
DISPLAY INVISIBLE (-7075 3250);
FORCEPROP 2 LAST PATH I162
J 0
(-7150 3425);
DISPLAY 1.021277 (-7150 3425);
PAINT ORANGE (-7150 3425);
DISPLAY INVISIBLE (-7150 3425);
FORCEADD OFFPAGE..5
(-7200 2650);
FORCEPROP 2 LAST $XR0 133 
J 0
(-7485 2650);
DISPLAY 0.638298 (-7485 2650);
PAINT MONO (-7485 2650);
FORCEPROP 2 LAST $XR1 146 
J 0
(-7605 2650);
DISPLAY 0.638298 (-7605 2650);
PAINT MONO (-7605 2650);
FORCEPROP 2 LAST $XR2 119 
J 0
(-7725 2650);
DISPLAY 0.638298 (-7725 2650);
PAINT MONO (-7725 2650);
FORCEPROP 2 LAST $XR3 182 
J 0
(-7845 2650);
DISPLAY 0.638298 (-7845 2650);
PAINT MONO (-7845 2650);
FORCEPROP 2 LAST CDS_LIB mstr_standard
J 0
(-7200 2650);
PAINT MONO (-7200 2650);
DISPLAY INVISIBLE (-7200 2650);
FORCEPROP 1 LAST OFFPAGE TRUE
J 0
(-6875 2525);
PAINT GREEN (-6875 2525);
DISPLAY INVISIBLE (-6875 2525);
FORCEPROP 1 LAST COMMENT_BODY TRUE
J 0
(-7100 2575);
DISPLAY 1.404255 (-7100 2575);
PAINT PEACH (-7100 2575);
DISPLAY INVISIBLE (-7100 2575);
FORCEPROP 2 LAST PATH I163
J 0
(-7150 2725);
DISPLAY 1.021277 (-7150 2725);
PAINT ORANGE (-7150 2725);
DISPLAY INVISIBLE (-7150 2725);
FORCEADD OFFPAGE..5
(-7200 3300);
FORCEPROP 2 LAST $XR0 136 
J 0
(-7485 3300);
DISPLAY 0.638298 (-7485 3300);
PAINT MONO (-7485 3300);
FORCEPROP 2 LAST $XR1 145 
J 0
(-7605 3300);
DISPLAY 0.638298 (-7605 3300);
PAINT MONO (-7605 3300);
FORCEPROP 2 LAST $XR2 157 
J 0
(-7725 3300);
DISPLAY 0.638298 (-7725 3300);
PAINT MONO (-7725 3300);
FORCEPROP 2 LAST CDS_LIB mstr_standard
J 0
(-7200 3300);
PAINT MONO (-7200 3300);
DISPLAY INVISIBLE (-7200 3300);
FORCEPROP 1 LAST OFFPAGE TRUE
J 0
(-6875 3175);
PAINT GREEN (-6875 3175);
DISPLAY INVISIBLE (-6875 3175);
FORCEPROP 1 LAST COMMENT_BODY TRUE
J 0
(-7100 3225);
DISPLAY 1.404255 (-7100 3225);
PAINT PEACH (-7100 3225);
DISPLAY INVISIBLE (-7100 3225);
FORCEPROP 2 LAST PATH I164
J 0
(-7150 3375);
DISPLAY 1.021277 (-7150 3375);
PAINT ORANGE (-7150 3375);
DISPLAY INVISIBLE (-7150 3375);
FORCEADD OFFPAGE..5
(-7200 3400);
FORCEPROP 2 LAST $XR0 138 
J 0
(-7485 3400);
DISPLAY 0.638298 (-7485 3400);
PAINT MONO (-7485 3400);
FORCEPROP 2 LAST CDS_LIB mstr_standard
J 0
(-7200 3400);
PAINT MONO (-7200 3400);
DISPLAY INVISIBLE (-7200 3400);
FORCEPROP 1 LAST OFFPAGE TRUE
J 0
(-6875 3275);
PAINT GREEN (-6875 3275);
DISPLAY INVISIBLE (-6875 3275);
FORCEPROP 1 LAST COMMENT_BODY TRUE
J 0
(-7100 3325);
DISPLAY 1.404255 (-7100 3325);
PAINT PEACH (-7100 3325);
DISPLAY INVISIBLE (-7100 3325);
FORCEPROP 2 LAST PATH I165
J 0
(-7150 3475);
DISPLAY 1.021277 (-7150 3475);
PAINT ORANGE (-7150 3475);
DISPLAY INVISIBLE (-7150 3475);
FORCEADD OFFPAGE..6
(-7200 3450);
FORCEPROP 2 LAST $XR0 138 
J 0
(-7480 3450);
DISPLAY 0.638298 (-7480 3450);
PAINT MONO (-7480 3450);
FORCEPROP 2 LAST CDS_LIB mstr_standard
J 0
(-7200 3450);
PAINT MONO (-7200 3450);
DISPLAY INVISIBLE (-7200 3450);
FORCEPROP 1 LAST OFFPAGE TRUE
J 0
(-6875 3325);
DISPLAY 0.872340 (-6875 3325);
PAINT GREEN (-6875 3325);
DISPLAY INVISIBLE (-6875 3325);
FORCEPROP 1 LAST COMMENT_BODY TRUE
J 0
(-7100 3375);
DISPLAY 0.872340 (-7100 3375);
PAINT GREEN (-7100 3375);
DISPLAY INVISIBLE (-7100 3375);
FORCEPROP 2 LAST PATH I166
J 0
(-7150 3525);
DISPLAY 1.021277 (-7150 3525);
PAINT ORANGE (-7150 3525);
DISPLAY INVISIBLE (-7150 3525);
FORCEADD OFFPAGE..1
(-7200 1300);
FORCEPROP 2 LAST $XR0 161 
J 0
(-7452 1300);
DISPLAY 0.638298 (-7452 1300);
PAINT MONO (-7452 1300);
FORCEPROP 2 LAST $XR1 181 
J 0
(-7572 1300);
DISPLAY 0.638298 (-7572 1300);
PAINT MONO (-7572 1300);
FORCEPROP 2 LAST $XR2 147 
J 0
(-7692 1300);
DISPLAY 0.638298 (-7692 1300);
PAINT MONO (-7692 1300);
FORCEPROP 2 LAST CDS_LIB mstr_standard
J 0
(-7200 1300);
PAINT MONO (-7200 1300);
DISPLAY INVISIBLE (-7200 1300);
FORCEPROP 1 LAST OFFPAGE TRUE
J 0
(-6875 1175);
PAINT GREEN (-6875 1175);
DISPLAY INVISIBLE (-6875 1175);
FORCEPROP 1 LAST COMMENT_BODY TRUE
J 0
(-7075 1200);
DISPLAY 1.404255 (-7075 1200);
PAINT PEACH (-7075 1200);
DISPLAY INVISIBLE (-7075 1200);
FORCEPROP 2 LAST PATH I167
J 0
(-7150 1375);
DISPLAY 1.021277 (-7150 1375);
PAINT ORANGE (-7150 1375);
DISPLAY INVISIBLE (-7150 1375);
FORCEADD OFFPAGE..1
(-7200 1200);
FORCEPROP 2 LAST $XR0 161 
J 0
(-7452 1200);
DISPLAY 0.638298 (-7452 1200);
PAINT MONO (-7452 1200);
FORCEPROP 2 LAST $XR1 181 
J 0
(-7572 1200);
DISPLAY 0.638298 (-7572 1200);
PAINT MONO (-7572 1200);
FORCEPROP 2 LAST $XR2 147 
J 0
(-7692 1200);
DISPLAY 0.638298 (-7692 1200);
PAINT MONO (-7692 1200);
FORCEPROP 2 LAST CDS_LIB mstr_standard
J 0
(-7200 1200);
PAINT MONO (-7200 1200);
DISPLAY INVISIBLE (-7200 1200);
FORCEPROP 1 LAST OFFPAGE TRUE
J 0
(-6875 1075);
PAINT GREEN (-6875 1075);
DISPLAY INVISIBLE (-6875 1075);
FORCEPROP 1 LAST COMMENT_BODY TRUE
J 0
(-7075 1100);
DISPLAY 1.404255 (-7075 1100);
PAINT PEACH (-7075 1100);
DISPLAY INVISIBLE (-7075 1100);
FORCEPROP 2 LAST PATH I168
J 0
(-7150 1275);
DISPLAY 1.021277 (-7150 1275);
PAINT ORANGE (-7150 1275);
DISPLAY INVISIBLE (-7150 1275);
FORCEADD OFFPAGE..1
(-7200 1400);
FORCEPROP 2 LAST $XR0 201 
J 0
(-7452 1400);
DISPLAY 0.638298 (-7452 1400);
PAINT MONO (-7452 1400);
FORCEPROP 2 LAST $XR1 95 
J 0
(-7542 1400);
DISPLAY 0.638298 (-7542 1400);
PAINT MONO (-7542 1400);
FORCEPROP 2 LAST $XR2 145 
J 0
(-7662 1400);
DISPLAY 0.638298 (-7662 1400);
PAINT MONO (-7662 1400);
FORCEPROP 2 LAST CDS_LIB mstr_standard
J 0
(-7200 1400);
PAINT MONO (-7200 1400);
DISPLAY INVISIBLE (-7200 1400);
FORCEPROP 1 LAST OFFPAGE TRUE
J 0
(-6875 1275);
PAINT GREEN (-6875 1275);
DISPLAY INVISIBLE (-6875 1275);
FORCEPROP 1 LAST COMMENT_BODY TRUE
J 0
(-7075 1300);
DISPLAY 1.404255 (-7075 1300);
PAINT PEACH (-7075 1300);
DISPLAY INVISIBLE (-7075 1300);
FORCEPROP 2 LAST PATH I169
J 0
(-7150 1475);
DISPLAY 1.021277 (-7150 1475);
PAINT ORANGE (-7150 1475);
DISPLAY INVISIBLE (-7150 1475);
FORCEADD OFFPAGE..1
(-7200 1450);
FORCEPROP 2 LAST $XR0 206 
J 0
(-7452 1450);
DISPLAY 0.638298 (-7452 1450);
PAINT MONO (-7452 1450);
FORCEPROP 2 LAST $XR1 95 
J 0
(-7542 1450);
DISPLAY 0.638298 (-7542 1450);
PAINT MONO (-7542 1450);
FORCEPROP 2 LAST $XR2 145 
J 0
(-7662 1450);
DISPLAY 0.638298 (-7662 1450);
PAINT MONO (-7662 1450);
FORCEPROP 2 LAST CDS_LIB mstr_standard
J 0
(-7200 1450);
PAINT MONO (-7200 1450);
DISPLAY INVISIBLE (-7200 1450);
FORCEPROP 1 LAST OFFPAGE TRUE
J 0
(-6875 1325);
PAINT GREEN (-6875 1325);
DISPLAY INVISIBLE (-6875 1325);
FORCEPROP 1 LAST COMMENT_BODY TRUE
J 0
(-7075 1350);
DISPLAY 1.404255 (-7075 1350);
PAINT PEACH (-7075 1350);
DISPLAY INVISIBLE (-7075 1350);
FORCEPROP 2 LAST PATH I170
J 0
(-7150 1525);
DISPLAY 1.021277 (-7150 1525);
PAINT ORANGE (-7150 1525);
DISPLAY INVISIBLE (-7150 1525);
FORCEADD OFFPAGE..1
(-7200 2350);
FORCEPROP 2 LAST $XR0 147 
J 0
(-7452 2350);
DISPLAY 0.638298 (-7452 2350);
PAINT MONO (-7452 2350);
FORCEPROP 2 LAST $XR1 190 
J 0
(-7572 2350);
DISPLAY 0.638298 (-7572 2350);
PAINT MONO (-7572 2350);
FORCEPROP 2 LAST $XR2 158 
J 0
(-7692 2350);
DISPLAY 0.638298 (-7692 2350);
PAINT MONO (-7692 2350);
FORCEPROP 2 LAST CDS_LIB mstr_standard
J 0
(-7200 2350);
PAINT MONO (-7200 2350);
DISPLAY INVISIBLE (-7200 2350);
FORCEPROP 1 LAST OFFPAGE TRUE
J 0
(-6875 2225);
PAINT GREEN (-6875 2225);
DISPLAY INVISIBLE (-6875 2225);
FORCEPROP 1 LAST COMMENT_BODY TRUE
J 0
(-7075 2250);
DISPLAY 1.404255 (-7075 2250);
PAINT PEACH (-7075 2250);
DISPLAY INVISIBLE (-7075 2250);
FORCEPROP 2 LAST PATH I173
J 0
(-7150 2425);
DISPLAY 1.021277 (-7150 2425);
PAINT ORANGE (-7150 2425);
DISPLAY INVISIBLE (-7150 2425);
FORCEADD OFFPAGE..5
R 2
(-1550 3600);
FORCEPROP 2 LAST $XR0 146 
J 0
(-1361 3600);
DISPLAY 0.638298 (-1361 3600);
PAINT MONO (-1361 3600);
FORCEPROP 2 LAST $XR1 155 
J 0
(-1241 3600);
DISPLAY 0.638298 (-1241 3600);
PAINT MONO (-1241 3600);
FORCEPROP 2 LAST CDS_LIB mstr_standard
J 0
(-1550 3600);
PAINT MONO (-1550 3600);
DISPLAY INVISIBLE (-1550 3600);
FORCEPROP 1 LAST OFFPAGE TRUE
J 2
(-1875 3475);
DISPLAY 0.872340 (-1875 3475);
PAINT GREEN (-1875 3475);
DISPLAY INVISIBLE (-1875 3475);
FORCEPROP 1 LAST COMMENT_BODY TRUE
J 2
(-1650 3525);
DISPLAY 0.872340 (-1650 3525);
PAINT GREEN (-1650 3525);
DISPLAY INVISIBLE (-1650 3525);
FORCEPROP 2 LAST PATH I174
J 0
(-1375 3675);
DISPLAY 1.021277 (-1375 3675);
PAINT ORANGE (-1375 3675);
DISPLAY INVISIBLE (-1375 3675);
FORCEADD OFFPAGE..5
R 2
(-1550 3550);
FORCEPROP 2 LAST $XR0 146 
J 0
(-1361 3550);
DISPLAY 0.638298 (-1361 3550);
PAINT MONO (-1361 3550);
FORCEPROP 2 LAST $XR1 155 
J 0
(-1241 3550);
DISPLAY 0.638298 (-1241 3550);
PAINT MONO (-1241 3550);
FORCEPROP 2 LAST CDS_LIB mstr_standard
J 0
(-1550 3550);
PAINT MONO (-1550 3550);
DISPLAY INVISIBLE (-1550 3550);
FORCEPROP 1 LAST OFFPAGE TRUE
J 2
(-1875 3425);
DISPLAY 0.872340 (-1875 3425);
PAINT GREEN (-1875 3425);
DISPLAY INVISIBLE (-1875 3425);
FORCEPROP 1 LAST COMMENT_BODY TRUE
J 2
(-1650 3475);
DISPLAY 0.872340 (-1650 3475);
PAINT GREEN (-1650 3475);
DISPLAY INVISIBLE (-1650 3475);
FORCEPROP 2 LAST PATH I175
J 0
(-1375 3625);
DISPLAY 1.021277 (-1375 3625);
PAINT ORANGE (-1375 3625);
DISPLAY INVISIBLE (-1375 3625);
FORCEADD OFFPAGE..5
R 2
(-1550 3500);
FORCEPROP 2 LAST $XR0 146 
J 0
(-1361 3500);
DISPLAY 0.638298 (-1361 3500);
PAINT MONO (-1361 3500);
FORCEPROP 2 LAST $XR1 155 
J 0
(-1241 3500);
DISPLAY 0.638298 (-1241 3500);
PAINT MONO (-1241 3500);
FORCEPROP 2 LAST CDS_LIB mstr_standard
J 0
(-1550 3500);
PAINT MONO (-1550 3500);
DISPLAY INVISIBLE (-1550 3500);
FORCEPROP 1 LAST OFFPAGE TRUE
J 2
(-1875 3375);
DISPLAY 0.872340 (-1875 3375);
PAINT GREEN (-1875 3375);
DISPLAY INVISIBLE (-1875 3375);
FORCEPROP 1 LAST COMMENT_BODY TRUE
J 2
(-1650 3425);
DISPLAY 0.872340 (-1650 3425);
PAINT GREEN (-1650 3425);
DISPLAY INVISIBLE (-1650 3425);
FORCEPROP 2 LAST PATH I176
J 0
(-1375 3575);
DISPLAY 1.021277 (-1375 3575);
PAINT ORANGE (-1375 3575);
DISPLAY INVISIBLE (-1375 3575);
FORCEADD OFFPAGE..5
R 2
(-1550 3450);
FORCEPROP 2 LAST $XR0 146 
J 0
(-1361 3450);
DISPLAY 0.638298 (-1361 3450);
PAINT MONO (-1361 3450);
FORCEPROP 2 LAST $XR1 155 
J 0
(-1241 3450);
DISPLAY 0.638298 (-1241 3450);
PAINT MONO (-1241 3450);
FORCEPROP 2 LAST CDS_LIB mstr_standard
J 0
(-1550 3450);
PAINT MONO (-1550 3450);
DISPLAY INVISIBLE (-1550 3450);
FORCEPROP 1 LAST OFFPAGE TRUE
J 2
(-1875 3325);
DISPLAY 0.872340 (-1875 3325);
PAINT GREEN (-1875 3325);
DISPLAY INVISIBLE (-1875 3325);
FORCEPROP 1 LAST COMMENT_BODY TRUE
J 2
(-1650 3375);
DISPLAY 0.872340 (-1650 3375);
PAINT GREEN (-1650 3375);
DISPLAY INVISIBLE (-1650 3375);
FORCEPROP 2 LAST PATH I177
J 0
(-1375 3525);
DISPLAY 1.021277 (-1375 3525);
PAINT ORANGE (-1375 3525);
DISPLAY INVISIBLE (-1375 3525);
FORCEADD OFFPAGE..5
R 2
(-1550 3400);
FORCEPROP 2 LAST $XR0 146 
J 0
(-1361 3400);
DISPLAY 0.638298 (-1361 3400);
PAINT MONO (-1361 3400);
FORCEPROP 2 LAST $XR1 155 
J 0
(-1241 3400);
DISPLAY 0.638298 (-1241 3400);
PAINT MONO (-1241 3400);
FORCEPROP 2 LAST CDS_LIB mstr_standard
J 0
(-1550 3400);
PAINT MONO (-1550 3400);
DISPLAY INVISIBLE (-1550 3400);
FORCEPROP 1 LAST OFFPAGE TRUE
J 2
(-1875 3275);
DISPLAY 0.872340 (-1875 3275);
PAINT GREEN (-1875 3275);
DISPLAY INVISIBLE (-1875 3275);
FORCEPROP 1 LAST COMMENT_BODY TRUE
J 2
(-1650 3325);
DISPLAY 0.872340 (-1650 3325);
PAINT GREEN (-1650 3325);
DISPLAY INVISIBLE (-1650 3325);
FORCEPROP 2 LAST PATH I178
J 0
(-1375 3475);
DISPLAY 1.021277 (-1375 3475);
PAINT ORANGE (-1375 3475);
DISPLAY INVISIBLE (-1375 3475);
FORCEADD OFFPAGE..5
R 2
(-1550 3350);
FORCEPROP 2 LAST $XR0 146 
J 0
(-1361 3350);
DISPLAY 0.638298 (-1361 3350);
PAINT MONO (-1361 3350);
FORCEPROP 2 LAST $XR1 155 
J 0
(-1241 3350);
DISPLAY 0.638298 (-1241 3350);
PAINT MONO (-1241 3350);
FORCEPROP 2 LAST CDS_LIB mstr_standard
J 0
(-1550 3350);
PAINT MONO (-1550 3350);
DISPLAY INVISIBLE (-1550 3350);
FORCEPROP 1 LAST OFFPAGE TRUE
J 2
(-1875 3225);
DISPLAY 0.872340 (-1875 3225);
PAINT GREEN (-1875 3225);
DISPLAY INVISIBLE (-1875 3225);
FORCEPROP 1 LAST COMMENT_BODY TRUE
J 2
(-1650 3275);
DISPLAY 0.872340 (-1650 3275);
PAINT GREEN (-1650 3275);
DISPLAY INVISIBLE (-1650 3275);
FORCEPROP 2 LAST PATH I179
J 0
(-1375 3425);
DISPLAY 1.021277 (-1375 3425);
PAINT ORANGE (-1375 3425);
DISPLAY INVISIBLE (-1375 3425);
FORCEADD OFFPAGE..5
R 2
(-1550 3300);
FORCEPROP 2 LAST $XR0 146 
J 0
(-1361 3300);
DISPLAY 0.638298 (-1361 3300);
PAINT MONO (-1361 3300);
FORCEPROP 2 LAST $XR1 155 
J 0
(-1241 3300);
DISPLAY 0.638298 (-1241 3300);
PAINT MONO (-1241 3300);
FORCEPROP 2 LAST CDS_LIB mstr_standard
J 0
(-1550 3300);
PAINT MONO (-1550 3300);
DISPLAY INVISIBLE (-1550 3300);
FORCEPROP 1 LAST OFFPAGE TRUE
J 2
(-1875 3175);
DISPLAY 0.872340 (-1875 3175);
PAINT GREEN (-1875 3175);
DISPLAY INVISIBLE (-1875 3175);
FORCEPROP 1 LAST COMMENT_BODY TRUE
J 2
(-1650 3225);
DISPLAY 0.872340 (-1650 3225);
PAINT GREEN (-1650 3225);
DISPLAY INVISIBLE (-1650 3225);
FORCEPROP 2 LAST PATH I180
J 0
(-1375 3375);
DISPLAY 1.021277 (-1375 3375);
PAINT ORANGE (-1375 3375);
DISPLAY INVISIBLE (-1375 3375);
FORCEADD OFFPAGE..5
R 2
(-1550 3250);
FORCEPROP 2 LAST $XR0 146 
J 0
(-1361 3250);
DISPLAY 0.638298 (-1361 3250);
PAINT MONO (-1361 3250);
FORCEPROP 2 LAST $XR1 155 
J 0
(-1241 3250);
DISPLAY 0.638298 (-1241 3250);
PAINT MONO (-1241 3250);
FORCEPROP 2 LAST CDS_LIB mstr_standard
J 0
(-1550 3250);
PAINT MONO (-1550 3250);
DISPLAY INVISIBLE (-1550 3250);
FORCEPROP 1 LAST OFFPAGE TRUE
J 2
(-1875 3125);
DISPLAY 0.872340 (-1875 3125);
PAINT GREEN (-1875 3125);
DISPLAY INVISIBLE (-1875 3125);
FORCEPROP 1 LAST COMMENT_BODY TRUE
J 2
(-1650 3175);
DISPLAY 0.872340 (-1650 3175);
PAINT GREEN (-1650 3175);
DISPLAY INVISIBLE (-1650 3175);
FORCEPROP 2 LAST PATH I181
J 0
(-1375 3325);
DISPLAY 1.021277 (-1375 3325);
PAINT ORANGE (-1375 3325);
DISPLAY INVISIBLE (-1375 3325);
FORCEADD OFFPAGE..1
R 2
(-1525 3150);
FORCEPROP 2 LAST $XR0 147 
J 0
(-1339 3150);
DISPLAY 0.638298 (-1339 3150);
PAINT MONO (-1339 3150);
FORCEPROP 2 LAST $XR1 190 
J 0
(-1219 3150);
DISPLAY 0.638298 (-1219 3150);
PAINT MONO (-1219 3150);
FORCEPROP 2 LAST $XR2 158 
J 0
(-1099 3150);
DISPLAY 0.638298 (-1099 3150);
PAINT MONO (-1099 3150);
FORCEPROP 2 LAST CDS_LIB mstr_standard
J 0
(-1525 3150);
PAINT MONO (-1525 3150);
DISPLAY INVISIBLE (-1525 3150);
FORCEPROP 1 LAST OFFPAGE TRUE
J 2
(-1850 3025);
PAINT GREEN (-1850 3025);
DISPLAY INVISIBLE (-1850 3025);
FORCEPROP 1 LAST COMMENT_BODY TRUE
J 2
(-1650 3050);
DISPLAY 1.404255 (-1650 3050);
PAINT PEACH (-1650 3050);
DISPLAY INVISIBLE (-1650 3050);
FORCEPROP 2 LAST PATH I182
J 0
(-1350 3225);
DISPLAY 1.021277 (-1350 3225);
PAINT ORANGE (-1350 3225);
DISPLAY INVISIBLE (-1350 3225);
FORCEADD OFFPAGE..1
R 2
(-1525 4250);
FORCEPROP 2 LAST $XR0 134 
J 0
(-1339 4250);
DISPLAY 0.638298 (-1339 4250);
PAINT MONO (-1339 4250);
FORCEPROP 2 LAST $XR1 144 
J 0
(-1219 4250);
DISPLAY 0.638298 (-1219 4250);
PAINT MONO (-1219 4250);
FORCEPROP 2 LAST $XR2 ?
J 0
(-1219 4250);
DISPLAY 0.638298 (-1219 4250);
PAINT MONO (-1219 4250);
FORCEPROP 2 LAST CDS_LIB mstr_standard
J 0
(-1525 4250);
PAINT MONO (-1525 4250);
DISPLAY INVISIBLE (-1525 4250);
FORCEPROP 1 LAST OFFPAGE TRUE
J 2
(-1850 4125);
PAINT GREEN (-1850 4125);
DISPLAY INVISIBLE (-1850 4125);
FORCEPROP 1 LAST COMMENT_BODY TRUE
J 2
(-1650 4150);
DISPLAY 1.404255 (-1650 4150);
PAINT PEACH (-1650 4150);
DISPLAY INVISIBLE (-1650 4150);
FORCEPROP 2 LAST PATH I183
J 0
(-1350 4325);
DISPLAY 1.021277 (-1350 4325);
PAINT ORANGE (-1350 4325);
DISPLAY INVISIBLE (-1350 4325);
FORCEADD OFFPAGE..4
(-1525 2700);
FORCEPROP 2 LAST $XR0 89 
J 0
(-1339 2700);
DISPLAY 0.638298 (-1339 2700);
PAINT MONO (-1339 2700);
FORCEPROP 2 LAST $XR1 144 
J 0
(-1249 2700);
DISPLAY 0.638298 (-1249 2700);
PAINT MONO (-1249 2700);
FORCEPROP 2 LAST CDS_LIB mstr_standard
J 0
(-1525 2700);
PAINT MONO (-1525 2700);
DISPLAY INVISIBLE (-1525 2700);
FORCEPROP 1 LAST OFFPAGE TRUE
J 0
(-1200 2575);
DISPLAY 0.872340 (-1200 2575);
PAINT GREEN (-1200 2575);
DISPLAY INVISIBLE (-1200 2575);
FORCEPROP 1 LAST COMMENT_BODY TRUE
J 0
(-1550 2600);
DISPLAY 0.872340 (-1550 2600);
PAINT GREEN (-1550 2600);
DISPLAY INVISIBLE (-1550 2600);
FORCEPROP 2 LAST PATH I184
J 0
(-1350 2775);
DISPLAY 1.021277 (-1350 2775);
PAINT ORANGE (-1350 2775);
DISPLAY INVISIBLE (-1350 2775);
FORCEADD OFFPAGE..2
(-1550 2750);
FORCEPROP 2 LAST $XR0 133 
J 0
(-1361 2750);
DISPLAY 0.638298 (-1361 2750);
PAINT MONO (-1361 2750);
FORCEPROP 2 LAST $XR1 145 
J 0
(-1241 2750);
DISPLAY 0.638298 (-1241 2750);
PAINT MONO (-1241 2750);
FORCEPROP 2 LAST $XR2 182 
J 0
(-1121 2750);
DISPLAY 0.638298 (-1121 2750);
PAINT MONO (-1121 2750);
FORCEPROP 2 LAST CDS_LIB mstr_standard
J 0
(-1550 2750);
PAINT MONO (-1550 2750);
DISPLAY INVISIBLE (-1550 2750);
FORCEPROP 1 LAST OFFPAGE TRUE
J 0
(-1225 2625);
DISPLAY 0.872340 (-1225 2625);
PAINT GREEN (-1225 2625);
DISPLAY INVISIBLE (-1225 2625);
FORCEPROP 1 LAST COMMENT_BODY TRUE
J 0
(-1595 2655);
DISPLAY 0.872340 (-1595 2655);
PAINT GREEN (-1595 2655);
DISPLAY INVISIBLE (-1595 2655);
FORCEPROP 2 LAST PATH I185
J 0
(-1375 2825);
DISPLAY 1.021277 (-1375 2825);
PAINT ORANGE (-1375 2825);
DISPLAY INVISIBLE (-1375 2825);
FORCEADD OFFPAGE..1
R 2
(-1525 3000);
FORCEPROP 2 LAST $XR0 144 
J 0
(-1339 3000);
DISPLAY 0.638298 (-1339 3000);
PAINT MONO (-1339 3000);
FORCEPROP 2 LAST CDS_LIB mstr_standard
J 0
(-1525 3000);
PAINT MONO (-1525 3000);
DISPLAY INVISIBLE (-1525 3000);
FORCEPROP 1 LAST OFFPAGE TRUE
J 2
(-1850 2875);
PAINT GREEN (-1850 2875);
DISPLAY INVISIBLE (-1850 2875);
FORCEPROP 1 LAST COMMENT_BODY TRUE
J 2
(-1650 2900);
DISPLAY 1.404255 (-1650 2900);
PAINT PEACH (-1650 2900);
DISPLAY INVISIBLE (-1650 2900);
FORCEPROP 2 LAST PATH I187
J 0
(-1350 3075);
DISPLAY 1.021277 (-1350 3075);
PAINT ORANGE (-1350 3075);
DISPLAY INVISIBLE (-1350 3075);
FORCEADD OFFPAGE..5
(-7200 1650);
FORCEPROP 2 LAST $XR0 147 
J 0
(-7485 1650);
DISPLAY 0.638298 (-7485 1650);
PAINT MONO (-7485 1650);
FORCEPROP 2 LAST $XR1 161 
J 0
(-7605 1650);
DISPLAY 0.638298 (-7605 1650);
PAINT MONO (-7605 1650);
FORCEPROP 2 LAST CDS_LIB mstr_standard
J 0
(-7200 1650);
PAINT MONO (-7200 1650);
DISPLAY INVISIBLE (-7200 1650);
FORCEPROP 1 LAST OFFPAGE TRUE
J 0
(-6875 1525);
PAINT GREEN (-6875 1525);
DISPLAY INVISIBLE (-6875 1525);
FORCEPROP 1 LAST COMMENT_BODY TRUE
J 0
(-7100 1575);
DISPLAY 1.404255 (-7100 1575);
PAINT PEACH (-7100 1575);
DISPLAY INVISIBLE (-7100 1575);
FORCEPROP 2 LAST PATH I188
J 0
(-7150 1725);
DISPLAY 1.021277 (-7150 1725);
PAINT ORANGE (-7150 1725);
DISPLAY INVISIBLE (-7150 1725);
FORCEADD OFFPAGE..5
(-7200 1600);
FORCEPROP 2 LAST $XR0 147 
J 0
(-7485 1600);
DISPLAY 0.638298 (-7485 1600);
PAINT MONO (-7485 1600);
FORCEPROP 2 LAST $XR1 161 
J 0
(-7605 1600);
DISPLAY 0.638298 (-7605 1600);
PAINT MONO (-7605 1600);
FORCEPROP 2 LAST CDS_LIB mstr_standard
J 0
(-7200 1600);
PAINT MONO (-7200 1600);
DISPLAY INVISIBLE (-7200 1600);
FORCEPROP 1 LAST OFFPAGE TRUE
J 0
(-6875 1475);
PAINT GREEN (-6875 1475);
DISPLAY INVISIBLE (-6875 1475);
FORCEPROP 1 LAST COMMENT_BODY TRUE
J 0
(-7100 1525);
DISPLAY 1.404255 (-7100 1525);
PAINT PEACH (-7100 1525);
DISPLAY INVISIBLE (-7100 1525);
FORCEPROP 2 LAST PATH I189
J 0
(-7150 1675);
DISPLAY 1.021277 (-7150 1675);
PAINT ORANGE (-7150 1675);
DISPLAY INVISIBLE (-7150 1675);
FORCEADD OFFPAGE..1
(-7200 1700);
FORCEPROP 2 LAST $XR0 190 
J 0
(-7452 1700);
DISPLAY 0.638298 (-7452 1700);
PAINT MONO (-7452 1700);
FORCEPROP 2 LAST $XR1 146 
J 0
(-7572 1700);
DISPLAY 0.638298 (-7572 1700);
PAINT MONO (-7572 1700);
FORCEPROP 2 LAST CDS_LIB mstr_standard
J 0
(-7200 1700);
PAINT MONO (-7200 1700);
DISPLAY INVISIBLE (-7200 1700);
FORCEPROP 1 LAST OFFPAGE TRUE
J 0
(-6875 1575);
PAINT GREEN (-6875 1575);
DISPLAY INVISIBLE (-6875 1575);
FORCEPROP 1 LAST COMMENT_BODY TRUE
J 0
(-7075 1600);
DISPLAY 1.404255 (-7075 1600);
PAINT PEACH (-7075 1600);
DISPLAY INVISIBLE (-7075 1600);
FORCEPROP 2 LAST PATH I190
J 0
(-7150 1775);
DISPLAY 1.021277 (-7150 1775);
PAINT ORANGE (-7150 1775);
DISPLAY INVISIBLE (-7150 1775);
FORCEADD OFFPAGE..1
(-7200 1750);
FORCEPROP 2 LAST $XR0 191 
J 0
(-7452 1750);
DISPLAY 0.638298 (-7452 1750);
PAINT MONO (-7452 1750);
FORCEPROP 2 LAST $XR1 148 
J 0
(-7572 1750);
DISPLAY 0.638298 (-7572 1750);
PAINT MONO (-7572 1750);
FORCEPROP 2 LAST CDS_LIB mstr_standard
J 0
(-7200 1750);
PAINT MONO (-7200 1750);
DISPLAY INVISIBLE (-7200 1750);
FORCEPROP 1 LAST OFFPAGE TRUE
J 0
(-6875 1625);
PAINT GREEN (-6875 1625);
DISPLAY INVISIBLE (-6875 1625);
FORCEPROP 1 LAST COMMENT_BODY TRUE
J 0
(-7075 1650);
DISPLAY 1.404255 (-7075 1650);
PAINT PEACH (-7075 1650);
DISPLAY INVISIBLE (-7075 1650);
FORCEPROP 2 LAST PATH I191
J 0
(-7150 1825);
DISPLAY 1.021277 (-7150 1825);
PAINT ORANGE (-7150 1825);
DISPLAY INVISIBLE (-7150 1825);
FORCEADD OFFPAGE..1
(-7200 1350);
FORCEPROP 2 LAST $XR0 161 
J 0
(-7452 1350);
DISPLAY 0.638298 (-7452 1350);
PAINT MONO (-7452 1350);
FORCEPROP 2 LAST $XR1 181 
J 0
(-7572 1350);
DISPLAY 0.638298 (-7572 1350);
PAINT MONO (-7572 1350);
FORCEPROP 2 LAST $XR2 147 
J 0
(-7692 1350);
DISPLAY 0.638298 (-7692 1350);
PAINT MONO (-7692 1350);
FORCEPROP 2 LAST CDS_LIB mstr_standard
J 0
(-7200 1350);
PAINT MONO (-7200 1350);
DISPLAY INVISIBLE (-7200 1350);
FORCEPROP 1 LAST OFFPAGE TRUE
J 0
(-6875 1225);
PAINT GREEN (-6875 1225);
DISPLAY INVISIBLE (-6875 1225);
FORCEPROP 1 LAST COMMENT_BODY TRUE
J 0
(-7075 1250);
DISPLAY 1.404255 (-7075 1250);
PAINT PEACH (-7075 1250);
DISPLAY INVISIBLE (-7075 1250);
FORCEPROP 2 LAST PATH I193
J 0
(-7150 1425);
DISPLAY 1.021277 (-7150 1425);
PAINT ORANGE (-7150 1425);
DISPLAY INVISIBLE (-7150 1425);
FORCEADD OFFPAGE..1
(-7200 1250);
FORCEPROP 2 LAST $XR0 161 
J 0
(-7452 1250);
DISPLAY 0.638298 (-7452 1250);
PAINT MONO (-7452 1250);
FORCEPROP 2 LAST $XR1 181 
J 0
(-7572 1250);
DISPLAY 0.638298 (-7572 1250);
PAINT MONO (-7572 1250);
FORCEPROP 2 LAST $XR2 147 
J 0
(-7692 1250);
DISPLAY 0.638298 (-7692 1250);
PAINT MONO (-7692 1250);
FORCEPROP 2 LAST CDS_LIB mstr_standard
J 0
(-7200 1250);
PAINT MONO (-7200 1250);
DISPLAY INVISIBLE (-7200 1250);
FORCEPROP 1 LAST OFFPAGE TRUE
J 0
(-6875 1125);
PAINT GREEN (-6875 1125);
DISPLAY INVISIBLE (-6875 1125);
FORCEPROP 1 LAST COMMENT_BODY TRUE
J 0
(-7075 1150);
DISPLAY 1.404255 (-7075 1150);
PAINT PEACH (-7075 1150);
DISPLAY INVISIBLE (-7075 1150);
FORCEPROP 2 LAST PATH I194
J 0
(-7150 1325);
DISPLAY 1.021277 (-7150 1325);
PAINT ORANGE (-7150 1325);
DISPLAY INVISIBLE (-7150 1325);
FORCEADD OFFPAGE..1
(-7200 3250);
FORCEPROP 2 LAST $XR0 135 
J 0
(-7482 3250);
DISPLAY 0.638298 (-7482 3250);
PAINT MONO (-7482 3250);
FORCEPROP 2 LAST $XR1 190 
J 0
(-7602 3250);
DISPLAY 0.638298 (-7602 3250);
PAINT MONO (-7602 3250);
FORCEPROP 2 LAST CDS_LIB mstr_standard
J 0
(-7200 3250);
PAINT MONO (-7200 3250);
DISPLAY INVISIBLE (-7200 3250);
FORCEPROP 1 LAST OFFPAGE TRUE
J 0
(-6875 3125);
PAINT GREEN (-6875 3125);
DISPLAY INVISIBLE (-6875 3125);
FORCEPROP 1 LAST COMMENT_BODY TRUE
J 0
(-7075 3150);
DISPLAY 1.404255 (-7075 3150);
PAINT PEACH (-7075 3150);
DISPLAY INVISIBLE (-7075 3150);
FORCEPROP 2 LAST PATH I195
J 0
(-7150 3325);
DISPLAY 1.021277 (-7150 3325);
PAINT ORANGE (-7150 3325);
DISPLAY INVISIBLE (-7150 3325);
FORCEADD OFFPAGE..5
(-7200 2800);
FORCEPROP 2 LAST $XR0 189 
J 0
(-7485 2800);
DISPLAY 0.638298 (-7485 2800);
PAINT MONO (-7485 2800);
FORCEPROP 2 LAST CDS_LIB mstr_standard
J 0
(-7200 2800);
PAINT MONO (-7200 2800);
DISPLAY INVISIBLE (-7200 2800);
FORCEPROP 1 LAST OFFPAGE TRUE
J 0
(-6875 2675);
DISPLAY 0.872340 (-6875 2675);
PAINT GREEN (-6875 2675);
DISPLAY INVISIBLE (-6875 2675);
FORCEPROP 1 LAST COMMENT_BODY TRUE
J 0
(-7100 2725);
DISPLAY 0.872340 (-7100 2725);
PAINT GREEN (-7100 2725);
DISPLAY INVISIBLE (-7100 2725);
FORCEPROP 2 LAST PATH I196
J 0
(-7150 2875);
DISPLAY 1.021277 (-7150 2875);
PAINT ORANGE (-7150 2875);
DISPLAY INVISIBLE (-7150 2875);
FORCEADD OFFPAGE..5
(-7200 2850);
FORCEPROP 2 LAST $XR0 189 
J 0
(-7485 2850);
DISPLAY 0.638298 (-7485 2850);
PAINT MONO (-7485 2850);
FORCEPROP 2 LAST CDS_LIB mstr_standard
J 0
(-7200 2850);
PAINT MONO (-7200 2850);
DISPLAY INVISIBLE (-7200 2850);
FORCEPROP 1 LAST OFFPAGE TRUE
J 0
(-6875 2725);
PAINT GREEN (-6875 2725);
DISPLAY INVISIBLE (-6875 2725);
FORCEPROP 1 LAST COMMENT_BODY TRUE
J 0
(-7100 2775);
DISPLAY 1.404255 (-7100 2775);
PAINT PEACH (-7100 2775);
DISPLAY INVISIBLE (-7100 2775);
FORCEPROP 2 LAST PATH I197
J 0
(-7150 2925);
DISPLAY 1.021277 (-7150 2925);
PAINT ORANGE (-7150 2925);
DISPLAY INVISIBLE (-7150 2925);
FORCEADD OFFPAGE..5
(-7200 2750);
FORCEPROP 2 LAST $XR0 189 
J 0
(-7485 2750);
DISPLAY 0.638298 (-7485 2750);
PAINT MONO (-7485 2750);
FORCEPROP 2 LAST CDS_LIB mstr_standard
J 0
(-7200 2750);
PAINT MONO (-7200 2750);
DISPLAY INVISIBLE (-7200 2750);
FORCEPROP 1 LAST OFFPAGE TRUE
J 0
(-6875 2625);
PAINT GREEN (-6875 2625);
DISPLAY INVISIBLE (-6875 2625);
FORCEPROP 1 LAST COMMENT_BODY TRUE
J 0
(-7100 2675);
DISPLAY 1.404255 (-7100 2675);
PAINT PEACH (-7100 2675);
DISPLAY INVISIBLE (-7100 2675);
FORCEPROP 2 LAST PATH I198
J 0
(-7150 2825);
DISPLAY 1.021277 (-7150 2825);
PAINT ORANGE (-7150 2825);
DISPLAY INVISIBLE (-7150 2825);
FORCEADD OFFPAGE..1
(-7200 2900);
FORCEPROP 2 LAST $XR0 189 
J 0
(-7482 2900);
DISPLAY 0.638298 (-7482 2900);
PAINT MONO (-7482 2900);
FORCEPROP 2 LAST CDS_LIB mstr_standard
J 0
(-7200 2900);
PAINT MONO (-7200 2900);
DISPLAY INVISIBLE (-7200 2900);
FORCEPROP 1 LAST OFFPAGE TRUE
J 0
(-6875 2775);
DISPLAY 0.872340 (-6875 2775);
PAINT GREEN (-6875 2775);
DISPLAY INVISIBLE (-6875 2775);
FORCEPROP 1 LAST COMMENT_BODY TRUE
J 0
(-7075 2800);
DISPLAY 0.872340 (-7075 2800);
PAINT GREEN (-7075 2800);
DISPLAY INVISIBLE (-7075 2800);
FORCEPROP 2 LAST PATH I199
J 0
(-7150 2975);
DISPLAY 1.021277 (-7150 2975);
PAINT ORANGE (-7150 2975);
DISPLAY INVISIBLE (-7150 2975);
FORCEADD OFFPAGE..1
(-7200 2700);
FORCEPROP 2 LAST $XR0 136 
J 0
(-7482 2700);
DISPLAY 0.638298 (-7482 2700);
PAINT MONO (-7482 2700);
FORCEPROP 2 LAST CDS_LIB mstr_standard
J 0
(-7200 2700);
PAINT MONO (-7200 2700);
DISPLAY INVISIBLE (-7200 2700);
FORCEPROP 1 LAST OFFPAGE TRUE
J 0
(-6875 2575);
PAINT GREEN (-6875 2575);
DISPLAY INVISIBLE (-6875 2575);
FORCEPROP 1 LAST COMMENT_BODY TRUE
J 0
(-7075 2600);
DISPLAY 1.404255 (-7075 2600);
PAINT PEACH (-7075 2600);
DISPLAY INVISIBLE (-7075 2600);
FORCEPROP 2 LAST PATH I200
J 0
(-7150 2775);
DISPLAY 1.021277 (-7150 2775);
PAINT ORANGE (-7150 2775);
DISPLAY INVISIBLE (-7150 2775);
FORCEADD OFFPAGE..5
R 2
(-1550 4100);
FORCEPROP 2 LAST $XR0 133 
J 0
(-1361 4100);
DISPLAY 0.638298 (-1361 4100);
PAINT MONO (-1361 4100);
FORCEPROP 2 LAST $XR1 146 
J 0
(-1241 4100);
DISPLAY 0.638298 (-1241 4100);
PAINT MONO (-1241 4100);
FORCEPROP 2 LAST $XR2 151 
J 0
(-1121 4100);
DISPLAY 0.638298 (-1121 4100);
PAINT MONO (-1121 4100);
FORCEPROP 2 LAST $XR3 175 
J 0
(-1121 4100);
DISPLAY 0.638298 (-1121 4100);
PAINT MONO (-1121 4100);
FORCEPROP 2 LAST CDS_LIB mstr_standard
J 0
(-1550 4100);
PAINT MONO (-1550 4100);
DISPLAY INVISIBLE (-1550 4100);
FORCEPROP 1 LAST OFFPAGE TRUE
J 2
(-1875 3975);
DISPLAY 0.872340 (-1875 3975);
PAINT GREEN (-1875 3975);
DISPLAY INVISIBLE (-1875 3975);
FORCEPROP 1 LAST COMMENT_BODY TRUE
J 2
(-1650 4025);
DISPLAY 0.872340 (-1650 4025);
PAINT GREEN (-1650 4025);
DISPLAY INVISIBLE (-1650 4025);
FORCEPROP 2 LAST PATH I201
J 0
(-1375 4175);
DISPLAY 1.021277 (-1375 4175);
PAINT ORANGE (-1375 4175);
DISPLAY INVISIBLE (-1375 4175);
FORCEADD OFFPAGE..5
(-7200 3200);
FORCEPROP 2 LAST $XR0 147 
J 0
(-7485 3200);
DISPLAY 0.638298 (-7485 3200);
PAINT MONO (-7485 3200);
FORCEPROP 2 LAST $XR1 191 
J 0
(-7605 3200);
DISPLAY 0.638298 (-7605 3200);
PAINT MONO (-7605 3200);
FORCEPROP 2 LAST CDS_LIB mstr_standard
J 0
(-7200 3200);
PAINT MONO (-7200 3200);
DISPLAY INVISIBLE (-7200 3200);
FORCEPROP 1 LAST OFFPAGE TRUE
J 0
(-6875 3075);
PAINT GREEN (-6875 3075);
DISPLAY INVISIBLE (-6875 3075);
FORCEPROP 1 LAST COMMENT_BODY TRUE
J 0
(-7100 3125);
DISPLAY 1.404255 (-7100 3125);
PAINT PEACH (-7100 3125);
DISPLAY INVISIBLE (-7100 3125);
FORCEPROP 2 LAST PATH I202
J 0
(-7150 3275);
DISPLAY 1.021277 (-7150 3275);
PAINT ORANGE (-7150 3275);
DISPLAY INVISIBLE (-7150 3275);
FORCEADD OFFPAGE..5
(-7200 3500);
FORCEPROP 2 LAST $XR0 133 
J 0
(-7485 3500);
DISPLAY 0.638298 (-7485 3500);
PAINT MONO (-7485 3500);
FORCEPROP 2 LAST $XR1 119 
J 0
(-7605 3500);
DISPLAY 0.638298 (-7605 3500);
PAINT MONO (-7605 3500);
FORCEPROP 2 LAST $XR2 143 
J 0
(-7725 3500);
DISPLAY 0.638298 (-7725 3500);
PAINT MONO (-7725 3500);
FORCEPROP 2 LAST CDS_LIB mstr_standard
J 0
(-7200 3500);
PAINT MONO (-7200 3500);
DISPLAY INVISIBLE (-7200 3500);
FORCEPROP 1 LAST OFFPAGE TRUE
J 0
(-6875 3375);
DISPLAY 0.872340 (-6875 3375);
PAINT GREEN (-6875 3375);
DISPLAY INVISIBLE (-6875 3375);
FORCEPROP 1 LAST COMMENT_BODY TRUE
J 0
(-7100 3425);
DISPLAY 0.872340 (-7100 3425);
PAINT GREEN (-7100 3425);
DISPLAY INVISIBLE (-7100 3425);
FORCEPROP 2 LAST PATH I208
J 0
(-7150 3575);
DISPLAY 1.021277 (-7150 3575);
PAINT ORANGE (-7150 3575);
DISPLAY INVISIBLE (-7150 3575);
FORCEPROP 2 LAST $XR3 146 
J 0
(-7725 3500);
DISPLAY 0.638298 (-7725 3500);
PAINT MONO (-7725 3500);
FORCEADD OFFPAGE..5
(-7200 3000);
FORCEPROP 2 LAST $XR0 178 
J 0
(-7485 3000);
DISPLAY 0.638298 (-7485 3000);
PAINT MONO (-7485 3000);
FORCEPROP 2 LAST CDS_LIB mstr_standard
J 0
(-7200 3000);
PAINT MONO (-7200 3000);
DISPLAY INVISIBLE (-7200 3000);
FORCEPROP 1 LAST OFFPAGE TRUE
J 0
(-6875 2875);
PAINT GREEN (-6875 2875);
DISPLAY INVISIBLE (-6875 2875);
FORCEPROP 1 LAST COMMENT_BODY TRUE
J 0
(-7100 2925);
DISPLAY 1.404255 (-7100 2925);
PAINT PEACH (-7100 2925);
DISPLAY INVISIBLE (-7100 2925);
FORCEPROP 2 LAST PATH I210
J 0
(-7150 3075);
DISPLAY 1.021277 (-7150 3075);
PAINT ORANGE (-7150 3075);
DISPLAY INVISIBLE (-7150 3075);
FORCEADD OFFPAGE..5
(-7200 2950);
FORCEPROP 2 LAST $XR0 178 
J 0
(-7485 2950);
DISPLAY 0.638298 (-7485 2950);
PAINT MONO (-7485 2950);
FORCEPROP 2 LAST CDS_LIB mstr_standard
J 0
(-7200 2950);
PAINT MONO (-7200 2950);
DISPLAY INVISIBLE (-7200 2950);
FORCEPROP 1 LAST OFFPAGE TRUE
J 0
(-6875 2825);
PAINT GREEN (-6875 2825);
DISPLAY INVISIBLE (-6875 2825);
FORCEPROP 1 LAST COMMENT_BODY TRUE
J 0
(-7100 2875);
DISPLAY 1.404255 (-7100 2875);
PAINT PEACH (-7100 2875);
DISPLAY INVISIBLE (-7100 2875);
FORCEPROP 2 LAST PATH I211
J 0
(-7150 3025);
DISPLAY 1.021277 (-7150 3025);
PAINT ORANGE (-7150 3025);
DISPLAY INVISIBLE (-7150 3025);
FORCEADD OFFPAGE..5
R 2
(-1550 4050);
FORCEPROP 2 LAST $XR0 126 
J 0
(-1361 4050);
DISPLAY 0.638298 (-1361 4050);
PAINT MONO (-1361 4050);
FORCEPROP 2 LAST $XR1 145 
J 0
(-1241 4050);
DISPLAY 0.638298 (-1241 4050);
PAINT MONO (-1241 4050);
FORCEPROP 2 LAST $XR2 200 
J 0
(-1121 4050);
DISPLAY 0.638298 (-1121 4050);
PAINT MONO (-1121 4050);
FORCEPROP 2 LAST CDS_LIB mstr_standard
J 0
(-1550 4050);
PAINT MONO (-1550 4050);
DISPLAY INVISIBLE (-1550 4050);
FORCEPROP 1 LAST OFFPAGE TRUE
J 2
(-1875 3925);
DISPLAY 0.872340 (-1875 3925);
PAINT GREEN (-1875 3925);
DISPLAY INVISIBLE (-1875 3925);
FORCEPROP 1 LAST COMMENT_BODY TRUE
J 2
(-1650 3975);
DISPLAY 0.872340 (-1650 3975);
PAINT GREEN (-1650 3975);
DISPLAY INVISIBLE (-1650 3975);
FORCEPROP 2 LAST PATH I212
J 0
(-1375 4125);
DISPLAY 1.021277 (-1375 4125);
PAINT ORANGE (-1375 4125);
DISPLAY INVISIBLE (-1375 4125);
FORCEADD OFFPAGE..5
(-7200 3600);
FORCEPROP 2 LAST $XR0 178 
J 0
(-7485 3600);
DISPLAY 0.638298 (-7485 3600);
PAINT MONO (-7485 3600);
FORCEPROP 2 LAST CDS_LIB mstr_standard
J 0
(-7200 3600);
PAINT MONO (-7200 3600);
DISPLAY INVISIBLE (-7200 3600);
FORCEPROP 1 LAST OFFPAGE TRUE
J 0
(-6875 3475);
PAINT GREEN (-6875 3475);
DISPLAY INVISIBLE (-6875 3475);
FORCEPROP 1 LAST COMMENT_BODY TRUE
J 0
(-7100 3525);
DISPLAY 1.404255 (-7100 3525);
PAINT PEACH (-7100 3525);
DISPLAY INVISIBLE (-7100 3525);
FORCEPROP 2 LAST PATH I213
J 0
(-7150 3675);
DISPLAY 1.021277 (-7150 3675);
PAINT ORANGE (-7150 3675);
DISPLAY INVISIBLE (-7150 3675);
FORCEADD OFFPAGE..5
(-7200 3550);
FORCEPROP 2 LAST $XR0 178 
J 0
(-7485 3550);
DISPLAY 0.638298 (-7485 3550);
PAINT MONO (-7485 3550);
FORCEPROP 2 LAST CDS_LIB mstr_standard
J 0
(-7200 3550);
PAINT MONO (-7200 3550);
DISPLAY INVISIBLE (-7200 3550);
FORCEPROP 1 LAST OFFPAGE TRUE
J 0
(-6875 3425);
PAINT GREEN (-6875 3425);
DISPLAY INVISIBLE (-6875 3425);
FORCEPROP 1 LAST COMMENT_BODY TRUE
J 0
(-7100 3475);
DISPLAY 1.404255 (-7100 3475);
PAINT PEACH (-7100 3475);
DISPLAY INVISIBLE (-7100 3475);
FORCEPROP 2 LAST PATH I215
J 0
(-7150 3625);
DISPLAY 1.021277 (-7150 3625);
PAINT ORANGE (-7150 3625);
DISPLAY INVISIBLE (-7150 3625);
FORCEADD OFFPAGE..5
(-7200 3100);
FORCEPROP 2 LAST $XR0 178 
J 0
(-7485 3100);
DISPLAY 0.638298 (-7485 3100);
PAINT MONO (-7485 3100);
FORCEPROP 2 LAST CDS_LIB mstr_standard
J 0
(-7200 3100);
PAINT MONO (-7200 3100);
DISPLAY INVISIBLE (-7200 3100);
FORCEPROP 1 LAST OFFPAGE TRUE
J 0
(-6875 2975);
PAINT GREEN (-6875 2975);
DISPLAY INVISIBLE (-6875 2975);
FORCEPROP 1 LAST COMMENT_BODY TRUE
J 0
(-7100 3025);
DISPLAY 1.404255 (-7100 3025);
PAINT PEACH (-7100 3025);
DISPLAY INVISIBLE (-7100 3025);
FORCEPROP 2 LAST PATH I217
J 0
(-7450 3150);
DISPLAY 1.021277 (-7450 3150);
PAINT ORANGE (-7450 3150);
DISPLAY INVISIBLE (-7450 3150);
FORCEADD RES..1
(-6375 3850);
FORCEPROP 1 LASTPIN (-6275 3850) $PN 2
J 0
(-6313 3862);
DISPLAY 0.617021 (-6313 3862);
PAINT ORANGE (-6313 3862);
FORCEPROP 1 LASTPIN (-6475 3850) $PN 1
J 0
(-6463 3862);
DISPLAY 0.617021 (-6463 3862);
PAINT ORANGE (-6463 3862);
FORCEPROP 1 LAST WATTAGE 1/16W
J 2
(-6050 3800);
DISPLAY 0.617021 (-6050 3800);
PAINT SKYBLUE (-6050 3800);
FORCEPROP 1 LAST MATERIAL CHIP
J 0
(-6425 3800);
DISPLAY 0.617021 (-6425 3800);
PAINT SKYBLUE (-6425 3800);
FORCEPROP 1 LAST PACK_TYPE 0402
J 0
(-6300 3800);
DISPLAY 0.617021 (-6300 3800);
PAINT SKYBLUE (-6300 3800);
FORCEPROP 1 LAST TOLERANCE 1%
J 0
(-6525 3800);
DISPLAY 0.617021 (-6525 3800);
PAINT SKYBLUE (-6525 3800);
FORCEPROP 1 LAST VALUE 33.2
J 2
(-6475 3850);
DISPLAY 0.617021 (-6475 3850);
PAINT SKYBLUE (-6475 3850);
FORCEPROP 1 LAST PART_NUMBER G21796-074
J 0
(-6025 3800);
DISPLAY 0.617021 (-6025 3800);
PAINT BLUE (-6025 3800);
FORCEPROP 1 LAST LOCATION R2M1
J 0
(-6400 3875);
DISPLAY 0.617021 (-6400 3875);
PAINT AQUA (-6400 3875);
FORCEPROP 1 LAST PATH I218
J 0
(-6425 4000);
DISPLAY 0.978723 (-6425 4000);
PAINT WHITE (-6425 4000);
DISPLAY INVISIBLE (-6425 4000);
FORCEPROP 2 LAST CDS_LIB mstr_discrete
J 0
(-6375 3850);
PAINT MONO (-6375 3850);
DISPLAY INVISIBLE (-6375 3850);
FORCEPROP 2 LAST SEC_TYPE 0402
J 0
(-6425 4050);
DISPLAY 1.021277 (-6425 4050);
PAINT ORANGE (-6425 4050);
DISPLAY INVISIBLE (-6425 4050);
FORCEPROP 2 LAST SEC 1
J 0
(-6425 4050);
DISPLAY 0.680851 (-6425 4050);
PAINT MONO (-6425 4050);
DISPLAY INVISIBLE (-6425 4050);
FORCEPROP 2 LAST CDS_LOCATION R2M1
J 0
(-6400 3875);
DISPLAY 0.617021 (-6400 3875);
PAINT AQUA (-6400 3875);
DISPLAY INVISIBLE (-6400 3875);
FORCEPROP 2 LAST ROOM CPLD
J 0
(-6425 3990);
DISPLAY 0.787234 (-6425 3990);
PAINT SKYBLUE (-6425 3990);
DISPLAY INVISIBLE (-6425 3990);
FORCEADD RES..1
(-6325 2050);
FORCEPROP 1 LASTPIN (-6225 2050) $PN 2
J 0
(-6263 2062);
DISPLAY 0.617021 (-6263 2062);
PAINT ORANGE (-6263 2062);
FORCEPROP 1 LASTPIN (-6425 2050) $PN 1
J 0
(-6413 2062);
DISPLAY 0.617021 (-6413 2062);
PAINT ORANGE (-6413 2062);
FORCEPROP 1 LAST WATTAGE 1/16W
J 2
(-6500 2000);
DISPLAY 0.617021 (-6500 2000);
PAINT SKYBLUE (-6500 2000);
FORCEPROP 1 LAST MATERIAL CHIP
J 0
(-6375 2000);
DISPLAY 0.617021 (-6375 2000);
PAINT SKYBLUE (-6375 2000);
FORCEPROP 1 LAST PACK_TYPE 0402
J 0
(-6250 2000);
DISPLAY 0.617021 (-6250 2000);
PAINT SKYBLUE (-6250 2000);
FORCEPROP 1 LAST TOLERANCE 1%
J 0
(-6475 2000);
DISPLAY 0.617021 (-6475 2000);
PAINT SKYBLUE (-6475 2000);
FORCEPROP 1 LAST VALUE 33.2
J 2
(-6475 2050);
DISPLAY 0.617021 (-6475 2050);
PAINT SKYBLUE (-6475 2050);
FORCEPROP 1 LAST PART_NUMBER G21796-074
J 0
(-6150 2000);
DISPLAY 0.617021 (-6150 2000);
PAINT BLUE (-6150 2000);
FORCEPROP 1 LAST LOCATION R2N26
J 0
(-6350 2075);
DISPLAY 0.617021 (-6350 2075);
PAINT AQUA (-6350 2075);
FORCEPROP 1 LAST PATH I219
J 0
(-6375 2200);
DISPLAY 0.978723 (-6375 2200);
PAINT WHITE (-6375 2200);
DISPLAY INVISIBLE (-6375 2200);
FORCEPROP 2 LAST CDS_LIB mstr_discrete
J 0
(-6325 2050);
PAINT MONO (-6325 2050);
DISPLAY INVISIBLE (-6325 2050);
FORCEPROP 2 LAST SEC_TYPE 0402
J 0
(-6375 2250);
DISPLAY 1.021277 (-6375 2250);
PAINT ORANGE (-6375 2250);
DISPLAY INVISIBLE (-6375 2250);
FORCEPROP 2 LAST SEC 1
J 0
(-6375 2250);
DISPLAY 0.680851 (-6375 2250);
PAINT MONO (-6375 2250);
DISPLAY INVISIBLE (-6375 2250);
FORCEPROP 2 LAST CDS_LOCATION R2N26
J 0
(-6350 2075);
DISPLAY 0.617021 (-6350 2075);
PAINT AQUA (-6350 2075);
DISPLAY INVISIBLE (-6350 2075);
FORCEPROP 2 LAST ROOM CPLD
J 0
(-6375 2190);
DISPLAY 0.787234 (-6375 2190);
PAINT SKYBLUE (-6375 2190);
DISPLAY INVISIBLE (-6375 2190);
FORCEADD OFFPAGE..2
(-1550 1250);
FORCEPROP 2 LAST $XR0 188 
J 0
(-1361 1250);
DISPLAY 0.638298 (-1361 1250);
PAINT MONO (-1361 1250);
FORCEPROP 2 LAST CDS_LIB mstr_standard
J 0
(-1550 1250);
PAINT ORANGE (-1550 1250);
DISPLAY INVISIBLE (-1550 1250);
FORCEPROP 1 LAST OFFPAGE TRUE
J 0
(-1225 1125);
DISPLAY 0.872340 (-1225 1125);
PAINT GREEN (-1225 1125);
DISPLAY INVISIBLE (-1225 1125);
FORCEPROP 1 LAST COMMENT_BODY TRUE
J 0
(-1595 1155);
DISPLAY 0.872340 (-1595 1155);
PAINT GREEN (-1595 1155);
DISPLAY INVISIBLE (-1595 1155);
FORCEPROP 2 LAST PATH I222
J 0
(-1375 1325);
DISPLAY 1.021277 (-1375 1325);
PAINT ORANGE (-1375 1325);
DISPLAY INVISIBLE (-1375 1325);
FORCEADD OFFPAGE..2
(-1550 1300);
FORCEPROP 2 LAST $XR0 188 
J 0
(-1361 1300);
DISPLAY 0.638298 (-1361 1300);
PAINT MONO (-1361 1300);
FORCEPROP 2 LAST CDS_LIB mstr_standard
J 0
(-1550 1300);
PAINT ORANGE (-1550 1300);
DISPLAY INVISIBLE (-1550 1300);
FORCEPROP 1 LAST OFFPAGE TRUE
J 0
(-1225 1175);
DISPLAY 0.872340 (-1225 1175);
PAINT GREEN (-1225 1175);
DISPLAY INVISIBLE (-1225 1175);
FORCEPROP 1 LAST COMMENT_BODY TRUE
J 0
(-1595 1205);
DISPLAY 0.872340 (-1595 1205);
PAINT GREEN (-1595 1205);
DISPLAY INVISIBLE (-1595 1205);
FORCEPROP 2 LAST PATH I223
J 0
(-1375 1375);
DISPLAY 1.021277 (-1375 1375);
PAINT ORANGE (-1375 1375);
DISPLAY INVISIBLE (-1375 1375);
FORCEADD OFFPAGE..2
(-1550 1350);
FORCEPROP 2 LAST $XR0 188 
J 0
(-1361 1350);
DISPLAY 0.638298 (-1361 1350);
PAINT MONO (-1361 1350);
FORCEPROP 2 LAST CDS_LIB mstr_standard
J 0
(-1550 1350);
PAINT ORANGE (-1550 1350);
DISPLAY INVISIBLE (-1550 1350);
FORCEPROP 1 LAST OFFPAGE TRUE
J 0
(-1225 1225);
DISPLAY 0.872340 (-1225 1225);
PAINT GREEN (-1225 1225);
DISPLAY INVISIBLE (-1225 1225);
FORCEPROP 1 LAST COMMENT_BODY TRUE
J 0
(-1595 1255);
DISPLAY 0.872340 (-1595 1255);
PAINT GREEN (-1595 1255);
DISPLAY INVISIBLE (-1595 1255);
FORCEPROP 2 LAST PATH I224
J 0
(-1375 1425);
DISPLAY 1.021277 (-1375 1425);
PAINT ORANGE (-1375 1425);
DISPLAY INVISIBLE (-1375 1425);
FORCEADD OFFPAGE..2
(-1550 1400);
FORCEPROP 2 LAST $XR0 188 
J 0
(-1361 1400);
DISPLAY 0.638298 (-1361 1400);
PAINT MONO (-1361 1400);
FORCEPROP 2 LAST CDS_LIB mstr_standard
J 0
(-1550 1400);
PAINT ORANGE (-1550 1400);
DISPLAY INVISIBLE (-1550 1400);
FORCEPROP 1 LAST OFFPAGE TRUE
J 0
(-1225 1275);
DISPLAY 0.872340 (-1225 1275);
PAINT GREEN (-1225 1275);
DISPLAY INVISIBLE (-1225 1275);
FORCEPROP 1 LAST COMMENT_BODY TRUE
J 0
(-1595 1305);
DISPLAY 0.872340 (-1595 1305);
PAINT GREEN (-1595 1305);
DISPLAY INVISIBLE (-1595 1305);
FORCEPROP 2 LAST PATH I225
J 0
(-1375 1475);
DISPLAY 1.021277 (-1375 1475);
PAINT ORANGE (-1375 1475);
DISPLAY INVISIBLE (-1375 1475);
FORCEADD OFFPAGE..2
(-1550 1600);
FORCEPROP 2 LAST $XR0 188 
J 0
(-1361 1600);
DISPLAY 0.638298 (-1361 1600);
PAINT MONO (-1361 1600);
FORCEPROP 2 LAST CDS_LIB mstr_standard
J 0
(-1550 1600);
PAINT ORANGE (-1550 1600);
DISPLAY INVISIBLE (-1550 1600);
FORCEPROP 1 LAST OFFPAGE TRUE
J 0
(-1225 1475);
DISPLAY 0.872340 (-1225 1475);
PAINT GREEN (-1225 1475);
DISPLAY INVISIBLE (-1225 1475);
FORCEPROP 1 LAST COMMENT_BODY TRUE
J 0
(-1595 1505);
DISPLAY 0.872340 (-1595 1505);
PAINT GREEN (-1595 1505);
DISPLAY INVISIBLE (-1595 1505);
FORCEPROP 2 LAST PATH I226
J 0
(-1375 1675);
DISPLAY 1.021277 (-1375 1675);
PAINT ORANGE (-1375 1675);
DISPLAY INVISIBLE (-1375 1675);
FORCEADD OFFPAGE..2
(-1550 1650);
FORCEPROP 2 LAST $XR0 188 
J 0
(-1361 1650);
DISPLAY 0.638298 (-1361 1650);
PAINT MONO (-1361 1650);
FORCEPROP 2 LAST CDS_LIB mstr_standard
J 0
(-1550 1650);
PAINT ORANGE (-1550 1650);
DISPLAY INVISIBLE (-1550 1650);
FORCEPROP 1 LAST OFFPAGE TRUE
J 0
(-1225 1525);
DISPLAY 0.872340 (-1225 1525);
PAINT GREEN (-1225 1525);
DISPLAY INVISIBLE (-1225 1525);
FORCEPROP 1 LAST COMMENT_BODY TRUE
J 0
(-1595 1555);
DISPLAY 0.872340 (-1595 1555);
PAINT GREEN (-1595 1555);
DISPLAY INVISIBLE (-1595 1555);
FORCEPROP 2 LAST PATH I227
J 0
(-1375 1725);
DISPLAY 1.021277 (-1375 1725);
PAINT ORANGE (-1375 1725);
DISPLAY INVISIBLE (-1375 1725);
FORCEADD OFFPAGE..2
(-1550 1750);
FORCEPROP 2 LAST $XR0 188 
J 0
(-1361 1750);
DISPLAY 0.638298 (-1361 1750);
PAINT MONO (-1361 1750);
FORCEPROP 2 LAST CDS_LIB mstr_standard
J 0
(-1550 1750);
PAINT ORANGE (-1550 1750);
DISPLAY INVISIBLE (-1550 1750);
FORCEPROP 1 LAST OFFPAGE TRUE
J 0
(-1225 1625);
DISPLAY 0.872340 (-1225 1625);
PAINT GREEN (-1225 1625);
DISPLAY INVISIBLE (-1225 1625);
FORCEPROP 1 LAST COMMENT_BODY TRUE
J 0
(-1595 1655);
DISPLAY 0.872340 (-1595 1655);
PAINT GREEN (-1595 1655);
DISPLAY INVISIBLE (-1595 1655);
FORCEPROP 2 LAST PATH I228
J 0
(-1375 1825);
DISPLAY 1.021277 (-1375 1825);
PAINT ORANGE (-1375 1825);
DISPLAY INVISIBLE (-1375 1825);
FORCEADD OFFPAGE..6
R 2
(-1575 1700);
FORCEPROP 2 LAST $XR0 188 
J 0
(-1361 1700);
DISPLAY 0.638298 (-1361 1700);
PAINT MONO (-1361 1700);
FORCEPROP 2 LAST CDS_LIB mstr_standard
J 0
(-1575 1700);
PAINT ORANGE (-1575 1700);
DISPLAY INVISIBLE (-1575 1700);
FORCEPROP 1 LAST OFFPAGE TRUE
J 2
(-1900 1575);
PAINT GREEN (-1900 1575);
DISPLAY INVISIBLE (-1900 1575);
FORCEPROP 1 LAST COMMENT_BODY TRUE
J 2
(-1675 1625);
DISPLAY 1.404255 (-1675 1625);
PAINT PEACH (-1675 1625);
DISPLAY INVISIBLE (-1675 1625);
FORCEPROP 2 LAST PATH I233
J 0
(-1375 1775);
DISPLAY 1.021277 (-1375 1775);
PAINT ORANGE (-1375 1775);
DISPLAY INVISIBLE (-1375 1775);
FORCEADD OFFPAGE..6
R 2
(-1575 1800);
FORCEPROP 2 LAST $XR0 188 
J 0
(-1361 1800);
DISPLAY 0.638298 (-1361 1800);
PAINT MONO (-1361 1800);
FORCEPROP 2 LAST CDS_LIB mstr_standard
J 0
(-1575 1800);
PAINT ORANGE (-1575 1800);
DISPLAY INVISIBLE (-1575 1800);
FORCEPROP 1 LAST OFFPAGE TRUE
J 2
(-1900 1675);
PAINT GREEN (-1900 1675);
DISPLAY INVISIBLE (-1900 1675);
FORCEPROP 1 LAST COMMENT_BODY TRUE
J 2
(-1675 1725);
DISPLAY 1.404255 (-1675 1725);
PAINT PEACH (-1675 1725);
DISPLAY INVISIBLE (-1675 1725);
FORCEPROP 2 LAST PATH I234
J 0
(-1375 1875);
DISPLAY 1.021277 (-1375 1875);
PAINT ORANGE (-1375 1875);
DISPLAY INVISIBLE (-1375 1875);
FORCEADD OFFPAGE..4
(-1525 2350);
FORCEPROP 2 LAST $XR0 188 
J 0
(-1339 2350);
DISPLAY 0.638298 (-1339 2350);
PAINT MONO (-1339 2350);
FORCEPROP 2 LAST CDS_LIB mstr_standard
J 0
(-1525 2350);
PAINT ORANGE (-1525 2350);
DISPLAY INVISIBLE (-1525 2350);
FORCEPROP 1 LAST OFFPAGE TRUE
J 0
(-1200 2225);
DISPLAY 0.872340 (-1200 2225);
PAINT GREEN (-1200 2225);
DISPLAY INVISIBLE (-1200 2225);
FORCEPROP 1 LAST COMMENT_BODY TRUE
J 0
(-1550 2250);
DISPLAY 0.872340 (-1550 2250);
PAINT PEACH (-1550 2250);
DISPLAY INVISIBLE (-1550 2250);
FORCEPROP 2 LAST PATH I235
J 0
(-1350 2425);
DISPLAY 1.021277 (-1350 2425);
PAINT ORANGE (-1350 2425);
DISPLAY INVISIBLE (-1350 2425);
FORCEADD OFFPAGE..4
(-1525 2250);
FORCEPROP 2 LAST $XR0 188 
J 0
(-1339 2250);
DISPLAY 0.638298 (-1339 2250);
PAINT MONO (-1339 2250);
FORCEPROP 2 LAST CDS_LIB mstr_standard
J 0
(-1525 2250);
PAINT ORANGE (-1525 2250);
DISPLAY INVISIBLE (-1525 2250);
FORCEPROP 1 LAST OFFPAGE TRUE
J 0
(-1200 2125);
DISPLAY 0.872340 (-1200 2125);
PAINT GREEN (-1200 2125);
DISPLAY INVISIBLE (-1200 2125);
FORCEPROP 1 LAST COMMENT_BODY TRUE
J 0
(-1550 2150);
DISPLAY 0.872340 (-1550 2150);
PAINT PEACH (-1550 2150);
DISPLAY INVISIBLE (-1550 2150);
FORCEPROP 2 LAST PATH I236
J 0
(-1350 2325);
DISPLAY 1.021277 (-1350 2325);
PAINT ORANGE (-1350 2325);
DISPLAY INVISIBLE (-1350 2325);
FORCEADD OFFPAGE..4
(-1525 2150);
FORCEPROP 2 LAST $XR0 188 
J 0
(-1339 2150);
DISPLAY 0.638298 (-1339 2150);
PAINT MONO (-1339 2150);
FORCEPROP 2 LAST CDS_LIB mstr_standard
J 0
(-1525 2150);
PAINT ORANGE (-1525 2150);
DISPLAY INVISIBLE (-1525 2150);
FORCEPROP 1 LAST OFFPAGE TRUE
J 0
(-1200 2025);
DISPLAY 0.872340 (-1200 2025);
PAINT GREEN (-1200 2025);
DISPLAY INVISIBLE (-1200 2025);
FORCEPROP 1 LAST COMMENT_BODY TRUE
J 0
(-1550 2050);
DISPLAY 0.872340 (-1550 2050);
PAINT PEACH (-1550 2050);
DISPLAY INVISIBLE (-1550 2050);
FORCEPROP 2 LAST PATH I237
J 0
(-1350 2225);
DISPLAY 1.021277 (-1350 2225);
PAINT ORANGE (-1350 2225);
DISPLAY INVISIBLE (-1350 2225);
FORCEADD OFFPAGE..4
(-1525 2050);
FORCEPROP 2 LAST $XR0 188 
J 0
(-1339 2050);
DISPLAY 0.638298 (-1339 2050);
PAINT MONO (-1339 2050);
FORCEPROP 2 LAST CDS_LIB mstr_standard
J 0
(-1525 2050);
PAINT ORANGE (-1525 2050);
DISPLAY INVISIBLE (-1525 2050);
FORCEPROP 1 LAST OFFPAGE TRUE
J 0
(-1200 1925);
DISPLAY 0.872340 (-1200 1925);
PAINT GREEN (-1200 1925);
DISPLAY INVISIBLE (-1200 1925);
FORCEPROP 1 LAST COMMENT_BODY TRUE
J 0
(-1550 1950);
DISPLAY 0.872340 (-1550 1950);
PAINT PEACH (-1550 1950);
DISPLAY INVISIBLE (-1550 1950);
FORCEPROP 2 LAST PATH I238
J 0
(-1350 2125);
DISPLAY 1.021277 (-1350 2125);
PAINT ORANGE (-1350 2125);
DISPLAY INVISIBLE (-1350 2125);
FORCEADD OFFPAGE..2
(-1550 1450);
FORCEPROP 2 LAST $XR0 188 
J 0
(-1361 1450);
DISPLAY 0.638298 (-1361 1450);
PAINT MONO (-1361 1450);
FORCEPROP 2 LAST CDS_LIB mstr_standard
J 0
(-1550 1450);
PAINT ORANGE (-1550 1450);
DISPLAY INVISIBLE (-1550 1450);
FORCEPROP 1 LAST OFFPAGE TRUE
J 0
(-1225 1325);
DISPLAY 0.872340 (-1225 1325);
PAINT GREEN (-1225 1325);
DISPLAY INVISIBLE (-1225 1325);
FORCEPROP 1 LAST COMMENT_BODY TRUE
J 0
(-1595 1355);
DISPLAY 0.872340 (-1595 1355);
PAINT GREEN (-1595 1355);
DISPLAY INVISIBLE (-1595 1355);
FORCEPROP 2 LAST PATH I246
J 0
(-1350 1500);
DISPLAY 1.021277 (-1350 1500);
PAINT ORANGE (-1350 1500);
DISPLAY INVISIBLE (-1350 1500);
FORCEADD OFFPAGE..2
(-1550 1500);
FORCEPROP 2 LAST $XR0 188 
J 0
(-1361 1500);
DISPLAY 0.638298 (-1361 1500);
PAINT MONO (-1361 1500);
FORCEPROP 2 LAST CDS_LIB mstr_standard
J 0
(-1550 1500);
PAINT ORANGE (-1550 1500);
DISPLAY INVISIBLE (-1550 1500);
FORCEPROP 1 LAST OFFPAGE TRUE
J 0
(-1225 1375);
DISPLAY 0.872340 (-1225 1375);
PAINT GREEN (-1225 1375);
DISPLAY INVISIBLE (-1225 1375);
FORCEPROP 1 LAST COMMENT_BODY TRUE
J 0
(-1595 1405);
DISPLAY 0.872340 (-1595 1405);
PAINT GREEN (-1595 1405);
DISPLAY INVISIBLE (-1595 1405);
FORCEPROP 2 LAST PATH I247
J 0
(-1350 1550);
DISPLAY 1.021277 (-1350 1550);
PAINT ORANGE (-1350 1550);
DISPLAY INVISIBLE (-1350 1550);
FORCEADD OFFPAGE..2
(-1550 1550);
FORCEPROP 2 LAST $XR0 188 
J 0
(-1361 1550);
DISPLAY 0.638298 (-1361 1550);
PAINT MONO (-1361 1550);
FORCEPROP 2 LAST CDS_LIB mstr_standard
J 0
(-1550 1550);
PAINT ORANGE (-1550 1550);
DISPLAY INVISIBLE (-1550 1550);
FORCEPROP 1 LAST OFFPAGE TRUE
J 0
(-1225 1425);
DISPLAY 0.872340 (-1225 1425);
PAINT GREEN (-1225 1425);
DISPLAY INVISIBLE (-1225 1425);
FORCEPROP 1 LAST COMMENT_BODY TRUE
J 0
(-1595 1455);
DISPLAY 0.872340 (-1595 1455);
PAINT GREEN (-1595 1455);
DISPLAY INVISIBLE (-1595 1455);
FORCEPROP 2 LAST PATH I248
J 0
(-1350 1600);
DISPLAY 1.021277 (-1350 1600);
PAINT ORANGE (-1350 1600);
DISPLAY INVISIBLE (-1350 1600);
FORCEADD OFFPAGE..2
(-1550 1850);
FORCEPROP 2 LAST $XR0 188 
J 0
(-1361 1850);
DISPLAY 0.638298 (-1361 1850);
PAINT MONO (-1361 1850);
FORCEPROP 2 LAST CDS_LIB mstr_standard
J 0
(-1550 1850);
PAINT ORANGE (-1550 1850);
DISPLAY INVISIBLE (-1550 1850);
FORCEPROP 1 LAST OFFPAGE TRUE
J 0
(-1225 1725);
DISPLAY 0.872340 (-1225 1725);
PAINT GREEN (-1225 1725);
DISPLAY INVISIBLE (-1225 1725);
FORCEPROP 1 LAST COMMENT_BODY TRUE
J 0
(-1595 1755);
DISPLAY 0.872340 (-1595 1755);
PAINT GREEN (-1595 1755);
DISPLAY INVISIBLE (-1595 1755);
FORCEPROP 2 LAST PATH I249
J 0
(-1350 1900);
DISPLAY 1.021277 (-1350 1900);
PAINT ORANGE (-1350 1900);
DISPLAY INVISIBLE (-1350 1900);
FORCEADD OFFPAGE..6
R 2
(-1575 1900);
FORCEPROP 2 LAST $XR0 188 
J 0
(-1361 1900);
DISPLAY 0.638298 (-1361 1900);
PAINT MONO (-1361 1900);
FORCEPROP 2 LAST CDS_LIB mstr_standard
J 0
(-1575 1900);
PAINT ORANGE (-1575 1900);
DISPLAY INVISIBLE (-1575 1900);
FORCEPROP 1 LAST OFFPAGE TRUE
J 2
(-1900 1775);
PAINT GREEN (-1900 1775);
DISPLAY INVISIBLE (-1900 1775);
FORCEPROP 1 LAST COMMENT_BODY TRUE
J 2
(-1675 1825);
DISPLAY 1.404255 (-1675 1825);
PAINT PEACH (-1675 1825);
DISPLAY INVISIBLE (-1675 1825);
FORCEPROP 2 LAST PATH I250
J 0
(-1350 1950);
DISPLAY 1.021277 (-1350 1950);
PAINT ORANGE (-1350 1950);
DISPLAY INVISIBLE (-1350 1950);
FORCEADD OFFPAGE..6
R 2
(-1575 2000);
FORCEPROP 2 LAST $XR0 188 
J 0
(-1361 2000);
DISPLAY 0.638298 (-1361 2000);
PAINT MONO (-1361 2000);
FORCEPROP 2 LAST CDS_LIB mstr_standard
J 0
(-1575 2000);
PAINT ORANGE (-1575 2000);
DISPLAY INVISIBLE (-1575 2000);
FORCEPROP 1 LAST OFFPAGE TRUE
J 2
(-1900 1875);
PAINT GREEN (-1900 1875);
DISPLAY INVISIBLE (-1900 1875);
FORCEPROP 1 LAST COMMENT_BODY TRUE
J 2
(-1675 1925);
DISPLAY 1.404255 (-1675 1925);
PAINT PEACH (-1675 1925);
DISPLAY INVISIBLE (-1675 1925);
FORCEPROP 2 LAST PATH I251
J 0
(-1350 2050);
DISPLAY 1.021277 (-1350 2050);
PAINT ORANGE (-1350 2050);
DISPLAY INVISIBLE (-1350 2050);
FORCEADD OFFPAGE..2
(-1550 1950);
FORCEPROP 2 LAST $XR0 188 
J 0
(-1361 1950);
DISPLAY 0.638298 (-1361 1950);
PAINT MONO (-1361 1950);
FORCEPROP 2 LAST CDS_LIB mstr_standard
J 0
(-1550 1950);
PAINT ORANGE (-1550 1950);
DISPLAY INVISIBLE (-1550 1950);
FORCEPROP 1 LAST OFFPAGE TRUE
J 0
(-1225 1825);
DISPLAY 0.872340 (-1225 1825);
PAINT GREEN (-1225 1825);
DISPLAY INVISIBLE (-1225 1825);
FORCEPROP 1 LAST COMMENT_BODY TRUE
J 0
(-1595 1855);
DISPLAY 0.872340 (-1595 1855);
PAINT GREEN (-1595 1855);
DISPLAY INVISIBLE (-1595 1855);
FORCEPROP 2 LAST PATH I252
J 0
(-1350 2000);
DISPLAY 1.021277 (-1350 2000);
PAINT ORANGE (-1350 2000);
DISPLAY INVISIBLE (-1350 2000);
FORCEADD OFFPAGE..1
(-7200 1550);
FORCEPROP 2 LAST $XR0 119 
J 0
(-7482 1550);
DISPLAY 0.638298 (-7482 1550);
PAINT MONO (-7482 1550);
FORCEPROP 2 LAST $XR1 133 
J 0
(-7602 1550);
DISPLAY 0.638298 (-7602 1550);
PAINT MONO (-7602 1550);
FORCEPROP 2 LAST $XR2 170 
J 0
(-7722 1550);
DISPLAY 0.638298 (-7722 1550);
PAINT MONO (-7722 1550);
FORCEPROP 2 LAST $XR3 95 
J 0
(-7812 1550);
DISPLAY 0.638298 (-7812 1550);
PAINT MONO (-7812 1550);
FORCEPROP 2 LAST $XR4 146 
J 0
(-7932 1550);
DISPLAY 0.638298 (-7932 1550);
PAINT MONO (-7932 1550);
FORCEPROP 2 LAST $XR5 ?
J 0
(-7932 1550);
DISPLAY 0.638298 (-7932 1550);
PAINT MONO (-7932 1550);
FORCEPROP 2 LAST CDS_LIB mstr_standard
J 0
(-7200 1550);
PAINT ORANGE (-7200 1550);
DISPLAY INVISIBLE (-7200 1550);
FORCEPROP 1 LAST OFFPAGE TRUE
J 0
(-6875 1425);
PAINT GREEN (-6875 1425);
DISPLAY INVISIBLE (-6875 1425);
FORCEPROP 1 LAST COMMENT_BODY TRUE
J 0
(-7075 1450);
DISPLAY 1.404255 (-7075 1450);
PAINT PEACH (-7075 1450);
DISPLAY INVISIBLE (-7075 1450);
FORCEPROP 2 LAST PATH I253
J 0
(-7450 1600);
DISPLAY 1.021277 (-7450 1600);
PAINT ORANGE (-7450 1600);
DISPLAY INVISIBLE (-7450 1600);
FORCEADD OFFPAGE..1
(-7200 1500);
FORCEPROP 2 LAST $XR0 191 
J 0
(-7452 1500);
DISPLAY 0.638298 (-7452 1500);
PAINT MONO (-7452 1500);
FORCEPROP 2 LAST $XR1 146 
J 0
(-7572 1500);
DISPLAY 0.638298 (-7572 1500);
PAINT MONO (-7572 1500);
FORCEPROP 2 LAST CDS_LIB mstr_standard
J 0
(-7200 1500);
PAINT ORANGE (-7200 1500);
DISPLAY INVISIBLE (-7200 1500);
FORCEPROP 1 LAST OFFPAGE TRUE
J 0
(-6875 1375);
PAINT GREEN (-6875 1375);
DISPLAY INVISIBLE (-6875 1375);
FORCEPROP 1 LAST COMMENT_BODY TRUE
J 0
(-7075 1400);
DISPLAY 1.404255 (-7075 1400);
PAINT PEACH (-7075 1400);
DISPLAY INVISIBLE (-7075 1400);
FORCEPROP 2 LAST PATH I254
J 0
(-7450 1550);
DISPLAY 1.021277 (-7450 1550);
PAINT ORANGE (-7450 1550);
DISPLAY INVISIBLE (-7450 1550);
FORCEADD OFFPAGE..1
R 2
(-1550 3750);
FORCEPROP 2 LAST $XR0 126 
J 0
(-1364 3750);
DISPLAY 0.638298 (-1364 3750);
PAINT MONO (-1364 3750);
FORCEPROP 2 LAST CDS_LIB mstr_standard
J 0
(-1550 3750);
PAINT ORANGE (-1550 3750);
DISPLAY INVISIBLE (-1550 3750);
FORCEPROP 1 LAST OFFPAGE TRUE
J 2
(-1875 3625);
PAINT GREEN (-1875 3625);
DISPLAY INVISIBLE (-1875 3625);
FORCEPROP 1 LAST COMMENT_BODY TRUE
J 2
(-1675 3650);
DISPLAY 1.404255 (-1675 3650);
PAINT PEACH (-1675 3650);
DISPLAY INVISIBLE (-1675 3650);
FORCEPROP 2 LAST PATH I259
J 0
(-1375 3825);
DISPLAY 1.021277 (-1375 3825);
PAINT ORANGE (-1375 3825);
DISPLAY INVISIBLE (-1375 3825);
FORCEADD OFFPAGE..1
R 2
(-1575 2800);
FORCEPROP 2 LAST $XR0 56 
J 0
(-1389 2800);
DISPLAY 0.638298 (-1389 2800);
PAINT MONO (-1389 2800);
FORCEPROP 2 LAST $XR1 133 
J 0
(-1299 2800);
DISPLAY 0.638298 (-1299 2800);
PAINT MONO (-1299 2800);
FORCEPROP 2 LAST $XR2 120 
J 0
(-1179 2800);
DISPLAY 0.638298 (-1179 2800);
PAINT MONO (-1179 2800);
FORCEPROP 2 LAST $XR3 145 
J 0
(-1059 2800);
DISPLAY 0.638298 (-1059 2800);
PAINT MONO (-1059 2800);
FORCEPROP 2 LAST CDS_LIB mstr_standard
J 0
(-1575 2800);
PAINT ORANGE (-1575 2800);
DISPLAY INVISIBLE (-1575 2800);
FORCEPROP 1 LAST OFFPAGE TRUE
J 2
(-1900 2675);
PAINT GREEN (-1900 2675);
DISPLAY INVISIBLE (-1900 2675);
FORCEPROP 1 LAST COMMENT_BODY TRUE
J 2
(-1700 2700);
DISPLAY 1.404255 (-1700 2700);
PAINT PEACH (-1700 2700);
DISPLAY INVISIBLE (-1700 2700);
FORCEPROP 2 LAST PATH I260
J 0
(-1400 2875);
DISPLAY 1.021277 (-1400 2875);
PAINT ORANGE (-1400 2875);
DISPLAY INVISIBLE (-1400 2875);
FORCEADD OFFPAGE..1
(-7200 3700);
FORCEPROP 2 LAST $XR0 22 
J 0
(-7421 3700);
DISPLAY 0.638298 (-7421 3700);
PAINT MONO (-7421 3700);
FORCEPROP 2 LAST $XR1 133 
J 0
(-7541 3700);
DISPLAY 0.638298 (-7541 3700);
PAINT MONO (-7541 3700);
FORCEPROP 2 LAST $XR2 118 
J 0
(-7661 3700);
DISPLAY 0.638298 (-7661 3700);
PAINT MONO (-7661 3700);
FORCEPROP 2 LAST $XR3 145 
J 0
(-7781 3700);
DISPLAY 0.638298 (-7781 3700);
PAINT MONO (-7781 3700);
FORCEPROP 2 LAST PATH I263
J 0
(-7400 3750);
DISPLAY 1.021277 (-7400 3750);
PAINT ORANGE (-7400 3750);
DISPLAY INVISIBLE (-7400 3750);
FORCEPROP 2 LAST CDS_LIB mstr_standard
J 0
(-7200 3700);
PAINT ORANGE (-7200 3700);
DISPLAY INVISIBLE (-7200 3700);
FORCEPROP 1 LAST OFFPAGE TRUE
J 0
(-6875 3575);
PAINT GREEN (-6875 3575);
DISPLAY INVISIBLE (-6875 3575);
FORCEPROP 1 LAST COMMENT_BODY TRUE
J 0
(-7075 3600);
DISPLAY 1.404255 (-7075 3600);
PAINT PEACH (-7075 3600);
DISPLAY INVISIBLE (-7075 3600);
FORCEADD OFFPAGE..5
(-7200 2300);
FORCEPROP 2 LAST $XR0 133 
J 0
(-7485 2300);
DISPLAY 0.638298 (-7485 2300);
PAINT MONO (-7485 2300);
FORCEPROP 2 LAST $XR1 190 
J 0
(-7605 2300);
DISPLAY 0.638298 (-7605 2300);
PAINT MONO (-7605 2300);
FORCEPROP 2 LAST PATH I264
J 0
(-7475 2350);
DISPLAY 1.021277 (-7475 2350);
PAINT ORANGE (-7475 2350);
DISPLAY INVISIBLE (-7475 2350);
FORCEPROP 2 LAST CDS_LIB mstr_standard
J 0
(-7200 2300);
PAINT ORANGE (-7200 2300);
DISPLAY INVISIBLE (-7200 2300);
FORCEPROP 1 LAST OFFPAGE TRUE
J 0
(-6875 2175);
DISPLAY 0.872340 (-6875 2175);
PAINT GREEN (-6875 2175);
DISPLAY INVISIBLE (-6875 2175);
FORCEPROP 1 LAST COMMENT_BODY TRUE
J 0
(-7100 2225);
DISPLAY 0.872340 (-7100 2225);
PAINT GREEN (-7100 2225);
DISPLAY INVISIBLE (-7100 2225);
FORCEADD OFFPAGE..1
(-7200 3750);
FORCEPROP 2 LAST $XR0 56 
J 0
(-7421 3750);
DISPLAY 0.638298 (-7421 3750);
PAINT MONO (-7421 3750);
FORCEPROP 2 LAST $XR1 133 
J 0
(-7541 3750);
DISPLAY 0.638298 (-7541 3750);
PAINT MONO (-7541 3750);
FORCEPROP 2 LAST $XR2 120 
J 0
(-7661 3750);
DISPLAY 0.638298 (-7661 3750);
PAINT MONO (-7661 3750);
FORCEPROP 2 LAST $XR3 145 
J 0
(-7781 3750);
DISPLAY 0.638298 (-7781 3750);
PAINT MONO (-7781 3750);
FORCEPROP 2 LAST CDS_LIB mstr_standard
J 0
(-7200 3750);
PAINT ORANGE (-7200 3750);
DISPLAY INVISIBLE (-7200 3750);
FORCEPROP 2 LAST PATH I265
J 0
(-6675 3800);
DISPLAY 1.021277 (-6675 3800);
PAINT ORANGE (-6675 3800);
DISPLAY INVISIBLE (-6675 3800);
FORCEPROP 1 LAST OFFPAGE TRUE
J 0
(-6875 3625);
DISPLAY 0.872340 (-6875 3625);
PAINT GREEN (-6875 3625);
DISPLAY INVISIBLE (-6875 3625);
FORCEPROP 1 LAST COMMENT_BODY TRUE
J 0
(-7075 3650);
DISPLAY 0.872340 (-7075 3650);
PAINT GREEN (-7075 3650);
DISPLAY INVISIBLE (-7075 3650);
FORCEADD GND..1
(-775 2600);
FORCEPROP 3 LASTPIN (-775 2650) SIG_NAME GND\g
J 0
(-765 2660);
DISPLAY 0.659574 (-765 2660);
PAINT MONO (-765 2660);
DISPLAY INVISIBLE (-765 2660);
FORCEPROP 1 LAST PATH I266
J 0
(-700 2600);
DISPLAY 0.872340 (-700 2600);
PAINT AQUA (-700 2600);
DISPLAY INVISIBLE (-700 2600);
FORCEPROP 1 LAST BODY_TYPE PLUMBING
J 0
(-820 2557);
DISPLAY 0.340426 (-820 2557);
PAINT GREEN (-820 2557);
DISPLAY INVISIBLE (-820 2557);
FORCEPROP 1 LAST SIZE 1B
J 0
(-700 2550);
DISPLAY 0.872340 (-700 2550);
PAINT AQUA (-700 2550);
DISPLAY INVISIBLE (-700 2550);
FORCEPROP 2 LAST CDS_LIB mstr_symbols
J 0
(-775 2600);
PAINT ORANGE (-775 2600);
DISPLAY INVISIBLE (-775 2600);
FORCEPROP 1 LAST HDL_POWER GND
J 0
(-775 2750);
DISPLAY 0.872340 (-775 2750);
PAINT GREEN (-775 2750);
DISPLAY INVISIBLE (-775 2750);
FORCEPROP 1 LAST VOLTAGE 0.0V
J 0
(-820 2557);
DISPLAY 0.340426 (-820 2557);
PAINT SKYBLUE (-820 2557);
DISPLAY INVISIBLE (-820 2557);
FORCEADD OFFPAGE..5
R 2
(-1550 3950);
FORCEPROP 2 LAST $XR0 138 
J 0
(-1361 3950);
DISPLAY 0.638298 (-1361 3950);
PAINT MONO (-1361 3950);
FORCEPROP 2 LAST CDS_LIB mstr_standard
J 2
(-1550 3950);
DISPLAY 1.212766 (-1550 3950);
PAINT ORANGE (-1550 3950);
DISPLAY INVISIBLE (-1550 3950);
FORCEPROP 1 LAST OFFPAGE TRUE
J 2
(-1875 3825);
DISPLAY 0.872340 (-1875 3825);
PAINT GREEN (-1875 3825);
DISPLAY INVISIBLE (-1875 3825);
FORCEPROP 1 LAST COMMENT_BODY TRUE
J 2
(-1650 3875);
DISPLAY 0.872340 (-1650 3875);
PAINT GREEN (-1650 3875);
DISPLAY INVISIBLE (-1650 3875);
FORCEPROP 2 LAST PATH I4
J 0
(-1350 4025);
DISPLAY 1.021277 (-1350 4025);
PAINT ORANGE (-1350 4025);
DISPLAY INVISIBLE (-1350 4025);
FORCEADD OFFPAGE..5
(-7200 3150);
FORCEPROP 2 LAST $XR0 177 
J 0
(-7485 3150);
DISPLAY 0.638298 (-7485 3150);
PAINT MONO (-7485 3150);
FORCEPROP 2 LAST CDS_LIB mstr_standard
J 0
(-7200 3150);
DISPLAY 1.212766 (-7200 3150);
PAINT ORANGE (-7200 3150);
DISPLAY INVISIBLE (-7200 3150);
FORCEPROP 1 LAST OFFPAGE TRUE
J 0
(-6875 3025);
PAINT GREEN (-6875 3025);
DISPLAY INVISIBLE (-6875 3025);
FORCEPROP 1 LAST COMMENT_BODY TRUE
J 0
(-7100 3075);
DISPLAY 1.404255 (-7100 3075);
PAINT PEACH (-7100 3075);
DISPLAY INVISIBLE (-7100 3075);
FORCEPROP 2 LAST PATH I43
J 0
(-7150 3225);
DISPLAY 1.021277 (-7150 3225);
PAINT ORANGE (-7150 3225);
DISPLAY INVISIBLE (-7150 3225);
FORCEADD OFFPAGE..6
R 2
(-1575 4000);
FORCEPROP 2 LAST $XR0 138 
J 0
(-1361 4000);
DISPLAY 0.638298 (-1361 4000);
PAINT MONO (-1361 4000);
FORCEPROP 2 LAST CDS_LIB mstr_standard
J 2
(-1575 4000);
DISPLAY 1.212766 (-1575 4000);
PAINT ORANGE (-1575 4000);
DISPLAY INVISIBLE (-1575 4000);
FORCEPROP 1 LAST OFFPAGE TRUE
J 2
(-1900 3875);
PAINT GREEN (-1900 3875);
DISPLAY INVISIBLE (-1900 3875);
FORCEPROP 1 LAST COMMENT_BODY TRUE
J 2
(-1675 3925);
DISPLAY 1.404255 (-1675 3925);
PAINT PEACH (-1675 3925);
DISPLAY INVISIBLE (-1675 3925);
FORCEPROP 2 LAST PATH I5
J 0
(-1375 4075);
DISPLAY 1.021277 (-1375 4075);
PAINT ORANGE (-1375 4075);
DISPLAY INVISIBLE (-1375 4075);
FORCEADD OFFPAGE..5
(-7200 4100);
FORCEPROP 2 LAST $XR0 177 
J 0
(-7485 4100);
DISPLAY 0.638298 (-7485 4100);
PAINT MONO (-7485 4100);
FORCEPROP 2 LAST CDS_LIB mstr_standard
J 0
(-7200 4100);
DISPLAY 1.212766 (-7200 4100);
PAINT ORANGE (-7200 4100);
DISPLAY INVISIBLE (-7200 4100);
FORCEPROP 1 LAST OFFPAGE TRUE
J 0
(-6875 3975);
PAINT GREEN (-6875 3975);
DISPLAY INVISIBLE (-6875 3975);
FORCEPROP 1 LAST COMMENT_BODY TRUE
J 0
(-7100 4025);
DISPLAY 1.404255 (-7100 4025);
PAINT PEACH (-7100 4025);
DISPLAY INVISIBLE (-7100 4025);
FORCEPROP 2 LAST PATH I53
J 0
(-7150 4175);
DISPLAY 1.021277 (-7150 4175);
PAINT ORANGE (-7150 4175);
DISPLAY INVISIBLE (-7150 4175);
FORCEADD OFFPAGE..1
(-7200 3850);
FORCEPROP 2 LAST $XR0 191 
J 0
(-7452 3850);
DISPLAY 0.638298 (-7452 3850);
PAINT MONO (-7452 3850);
FORCEPROP 2 LAST CDS_LIB mstr_standard
J 0
(-7200 3850);
DISPLAY 1.212766 (-7200 3850);
PAINT ORANGE (-7200 3850);
DISPLAY INVISIBLE (-7200 3850);
FORCEPROP 1 LAST OFFPAGE TRUE
J 0
(-6875 3725);
DISPLAY 0.872340 (-6875 3725);
PAINT GREEN (-6875 3725);
DISPLAY INVISIBLE (-6875 3725);
FORCEPROP 1 LAST COMMENT_BODY TRUE
J 0
(-7075 3750);
DISPLAY 0.872340 (-7075 3750);
PAINT GREEN (-7075 3750);
DISPLAY INVISIBLE (-7075 3750);
FORCEPROP 2 LAST PATH I54
J 0
(-7500 3900);
DISPLAY 1.021277 (-7500 3900);
PAINT ORANGE (-7500 3900);
DISPLAY INVISIBLE (-7500 3900);
FORCEADD OFFPAGE..1
(-7200 2250);
FORCEPROP 2 LAST $XR0 168 
J 0
(-7482 2250);
DISPLAY 0.638298 (-7482 2250);
PAINT MONO (-7482 2250);
FORCEPROP 2 LAST $XR1 144 
J 0
(-7602 2250);
DISPLAY 0.638298 (-7602 2250);
PAINT MONO (-7602 2250);
FORCEPROP 2 LAST $XR2 190 
J 0
(-7722 2250);
DISPLAY 0.638298 (-7722 2250);
PAINT MONO (-7722 2250);
FORCEPROP 2 LAST CDS_LIB mstr_standard
J 0
(-7200 2250);
DISPLAY 1.212766 (-7200 2250);
PAINT ORANGE (-7200 2250);
DISPLAY INVISIBLE (-7200 2250);
FORCEPROP 1 LAST OFFPAGE TRUE
J 0
(-6875 2125);
DISPLAY 0.872340 (-6875 2125);
PAINT GREEN (-6875 2125);
DISPLAY INVISIBLE (-6875 2125);
FORCEPROP 1 LAST COMMENT_BODY TRUE
J 0
(-7075 2150);
DISPLAY 0.872340 (-7075 2150);
PAINT GREEN (-7075 2150);
DISPLAY INVISIBLE (-7075 2150);
FORCEPROP 2 LAST PATH I68
J 0
(-7450 2300);
DISPLAY 1.021277 (-7450 2300);
PAINT ORANGE (-7450 2300);
DISPLAY INVISIBLE (-7450 2300);
FORCEADD OFFPAGE..1
(-7200 2200);
FORCEPROP 2 LAST $XR3 ?
J 0
(-7692 2200);
DISPLAY 0.638298 (-7692 2200);
PAINT MONO (-7692 2200);
FORCEPROP 2 LAST $XR0 119 
J 0
(-7452 2200);
DISPLAY 0.638298 (-7452 2200);
PAINT MONO (-7452 2200);
FORCEPROP 2 LAST $XR1 146 
J 0
(-7572 2200);
DISPLAY 0.638298 (-7572 2200);
PAINT MONO (-7572 2200);
FORCEPROP 2 LAST $XR2 170 
J 0
(-7692 2200);
DISPLAY 0.638298 (-7692 2200);
PAINT MONO (-7692 2200);
FORCEPROP 2 LAST CDS_LIB mstr_standard
J 0
(-7200 2200);
DISPLAY 1.212766 (-7200 2200);
PAINT ORANGE (-7200 2200);
DISPLAY INVISIBLE (-7200 2200);
FORCEPROP 1 LAST OFFPAGE TRUE
J 0
(-6875 2075);
PAINT GREEN (-6875 2075);
DISPLAY INVISIBLE (-6875 2075);
FORCEPROP 1 LAST COMMENT_BODY TRUE
J 0
(-7075 2100);
DISPLAY 1.404255 (-7075 2100);
PAINT PEACH (-7075 2100);
DISPLAY INVISIBLE (-7075 2100);
FORCEPROP 2 LAST PATH I69
J 0
(-7450 2250);
DISPLAY 1.021277 (-7450 2250);
PAINT ORANGE (-7450 2250);
DISPLAY INVISIBLE (-7450 2250);
FORCEADD OFFPAGE..6
R 2
(-1575 3700);
FORCEPROP 2 LAST $XR0 138 
J 0
(-1361 3700);
DISPLAY 0.638298 (-1361 3700);
PAINT MONO (-1361 3700);
FORCEPROP 2 LAST CDS_LIB mstr_standard
J 2
(-1575 3700);
DISPLAY 1.212766 (-1575 3700);
PAINT ORANGE (-1575 3700);
DISPLAY INVISIBLE (-1575 3700);
FORCEPROP 1 LAST OFFPAGE TRUE
J 2
(-1900 3575);
PAINT GREEN (-1900 3575);
DISPLAY INVISIBLE (-1900 3575);
FORCEPROP 1 LAST COMMENT_BODY TRUE
J 2
(-1675 3625);
DISPLAY 1.404255 (-1675 3625);
PAINT PEACH (-1675 3625);
DISPLAY INVISIBLE (-1675 3625);
FORCEPROP 2 LAST PATH I7
J 0
(-1375 3775);
DISPLAY 1.021277 (-1375 3775);
PAINT ORANGE (-1375 3775);
DISPLAY INVISIBLE (-1375 3775);
FORCEADD OFFPAGE..5
(-7200 2150);
FORCEPROP 2 LAST $XR0 133 
J 0
(-7485 2150);
DISPLAY 0.638298 (-7485 2150);
PAINT MONO (-7485 2150);
FORCEPROP 2 LAST $XR1 120 
J 0
(-7605 2150);
DISPLAY 0.638298 (-7605 2150);
PAINT MONO (-7605 2150);
FORCEPROP 2 LAST $XR2 145 
J 0
(-7725 2150);
DISPLAY 0.638298 (-7725 2150);
PAINT MONO (-7725 2150);
FORCEPROP 2 LAST $XR3 ?
J 0
(-7725 2150);
DISPLAY 0.638298 (-7725 2150);
PAINT MONO (-7725 2150);
FORCEPROP 2 LAST CDS_LIB mstr_standard
J 0
(-7200 2150);
DISPLAY 1.212766 (-7200 2150);
PAINT ORANGE (-7200 2150);
DISPLAY INVISIBLE (-7200 2150);
FORCEPROP 1 LAST OFFPAGE TRUE
J 0
(-6875 2025);
PAINT GREEN (-6875 2025);
DISPLAY INVISIBLE (-6875 2025);
FORCEPROP 1 LAST COMMENT_BODY TRUE
J 0
(-7100 2075);
DISPLAY 1.404255 (-7100 2075);
PAINT PEACH (-7100 2075);
DISPLAY INVISIBLE (-7100 2075);
FORCEPROP 2 LAST PATH I70
J 0
(-7150 2225);
DISPLAY 1.021277 (-7150 2225);
PAINT ORANGE (-7150 2225);
DISPLAY INVISIBLE (-7150 2225);
FORCEADD OFFPAGE..5
(-7200 2100);
FORCEPROP 2 LAST $XR0 157 
J 0
(-7485 2100);
DISPLAY 0.638298 (-7485 2100);
PAINT MONO (-7485 2100);
FORCEPROP 2 LAST CDS_LIB mstr_standard
J 0
(-7200 2100);
DISPLAY 1.212766 (-7200 2100);
PAINT ORANGE (-7200 2100);
DISPLAY INVISIBLE (-7200 2100);
FORCEPROP 1 LAST OFFPAGE TRUE
J 0
(-6875 1975);
PAINT GREEN (-6875 1975);
DISPLAY INVISIBLE (-6875 1975);
FORCEPROP 1 LAST COMMENT_BODY TRUE
J 0
(-7100 2025);
DISPLAY 1.404255 (-7100 2025);
PAINT PEACH (-7100 2025);
DISPLAY INVISIBLE (-7100 2025);
FORCEPROP 2 LAST PATH I71
J 0
(-7150 2175);
DISPLAY 1.021277 (-7150 2175);
PAINT ORANGE (-7150 2175);
DISPLAY INVISIBLE (-7150 2175);
FORCEADD OFFPAGE..5
(-7200 2050);
FORCEPROP 2 LAST $XR0 89 
J 0
(-7454 2050);
DISPLAY 0.638298 (-7454 2050);
PAINT MONO (-7454 2050);
FORCEPROP 2 LAST $XR1 191 
J 0
(-7574 2050);
DISPLAY 0.638298 (-7574 2050);
PAINT MONO (-7574 2050);
FORCEPROP 2 LAST CDS_LIB mstr_standard
J 0
(-7200 2050);
DISPLAY 1.212766 (-7200 2050);
PAINT ORANGE (-7200 2050);
DISPLAY INVISIBLE (-7200 2050);
FORCEPROP 1 LAST OFFPAGE TRUE
J 0
(-6875 1925);
PAINT GREEN (-6875 1925);
DISPLAY INVISIBLE (-6875 1925);
FORCEPROP 1 LAST COMMENT_BODY TRUE
J 0
(-7100 1975);
DISPLAY 1.404255 (-7100 1975);
PAINT PEACH (-7100 1975);
DISPLAY INVISIBLE (-7100 1975);
FORCEPROP 2 LAST PATH I72
J 0
(-7450 2100);
DISPLAY 1.021277 (-7450 2100);
PAINT ORANGE (-7450 2100);
DISPLAY INVISIBLE (-7450 2100);
FORCEADD OFFPAGE..1
(-7200 2000);
FORCEPROP 2 LAST $XR0 164 
J 0
(-7482 2000);
DISPLAY 0.638298 (-7482 2000);
PAINT MONO (-7482 2000);
FORCEPROP 2 LAST $XR1 147 
J 0
(-7602 2000);
DISPLAY 0.638298 (-7602 2000);
PAINT MONO (-7602 2000);
FORCEPROP 2 LAST CDS_LIB mstr_standard
J 0
(-7200 2000);
DISPLAY 1.212766 (-7200 2000);
PAINT ORANGE (-7200 2000);
DISPLAY INVISIBLE (-7200 2000);
FORCEPROP 1 LAST OFFPAGE TRUE
J 0
(-6875 1875);
PAINT GREEN (-6875 1875);
DISPLAY INVISIBLE (-6875 1875);
FORCEPROP 1 LAST COMMENT_BODY TRUE
J 0
(-7075 1900);
DISPLAY 1.404255 (-7075 1900);
PAINT PEACH (-7075 1900);
DISPLAY INVISIBLE (-7075 1900);
FORCEPROP 2 LAST PATH I73
J 0
(-7150 2075);
DISPLAY 1.021277 (-7150 2075);
PAINT ORANGE (-7150 2075);
DISPLAY INVISIBLE (-7150 2075);
FORCEADD OFFPAGE..1
(-7200 1900);
FORCEPROP 2 LAST $XR0 164 
J 0
(-7452 1900);
DISPLAY 0.638298 (-7452 1900);
PAINT MONO (-7452 1900);
FORCEPROP 2 LAST $XR1 147 
J 0
(-7572 1900);
DISPLAY 0.638298 (-7572 1900);
PAINT MONO (-7572 1900);
FORCEPROP 2 LAST CDS_LIB mstr_standard
J 0
(-7200 1900);
DISPLAY 1.212766 (-7200 1900);
PAINT ORANGE (-7200 1900);
DISPLAY INVISIBLE (-7200 1900);
FORCEPROP 1 LAST OFFPAGE TRUE
J 0
(-6875 1775);
PAINT GREEN (-6875 1775);
DISPLAY INVISIBLE (-6875 1775);
FORCEPROP 1 LAST COMMENT_BODY TRUE
J 0
(-7075 1800);
DISPLAY 1.404255 (-7075 1800);
PAINT PEACH (-7075 1800);
DISPLAY INVISIBLE (-7075 1800);
FORCEPROP 2 LAST PATH I74
J 0
(-7150 1975);
DISPLAY 1.021277 (-7150 1975);
PAINT ORANGE (-7150 1975);
DISPLAY INVISIBLE (-7150 1975);
FORCEADD OFFPAGE..1
(-7200 1950);
FORCEPROP 2 LAST $XR0 164 
J 0
(-7452 1950);
DISPLAY 0.638298 (-7452 1950);
PAINT MONO (-7452 1950);
FORCEPROP 2 LAST $XR1 147 
J 0
(-7572 1950);
DISPLAY 0.638298 (-7572 1950);
PAINT MONO (-7572 1950);
FORCEPROP 2 LAST CDS_LIB mstr_standard
J 0
(-7200 1950);
DISPLAY 1.212766 (-7200 1950);
PAINT ORANGE (-7200 1950);
DISPLAY INVISIBLE (-7200 1950);
FORCEPROP 1 LAST OFFPAGE TRUE
J 0
(-6875 1825);
PAINT GREEN (-6875 1825);
DISPLAY INVISIBLE (-6875 1825);
FORCEPROP 1 LAST COMMENT_BODY TRUE
J 0
(-7075 1850);
DISPLAY 1.404255 (-7075 1850);
PAINT PEACH (-7075 1850);
DISPLAY INVISIBLE (-7075 1850);
FORCEPROP 2 LAST PATH I75
J 0
(-7150 2025);
DISPLAY 1.021277 (-7150 2025);
PAINT ORANGE (-7150 2025);
DISPLAY INVISIBLE (-7150 2025);
FORCEADD OFFPAGE..1
(-7200 1850);
FORCEPROP 2 LAST $XR0 164 
J 0
(-7452 1850);
DISPLAY 0.638298 (-7452 1850);
PAINT MONO (-7452 1850);
FORCEPROP 2 LAST $XR1 147 
J 0
(-7572 1850);
DISPLAY 0.638298 (-7572 1850);
PAINT MONO (-7572 1850);
FORCEPROP 2 LAST CDS_LIB mstr_standard
J 0
(-7200 1850);
DISPLAY 1.212766 (-7200 1850);
PAINT ORANGE (-7200 1850);
DISPLAY INVISIBLE (-7200 1850);
FORCEPROP 1 LAST OFFPAGE TRUE
J 0
(-6875 1725);
PAINT GREEN (-6875 1725);
DISPLAY INVISIBLE (-6875 1725);
FORCEPROP 1 LAST COMMENT_BODY TRUE
J 0
(-7075 1750);
DISPLAY 1.404255 (-7075 1750);
PAINT PEACH (-7075 1750);
DISPLAY INVISIBLE (-7075 1750);
FORCEPROP 2 LAST PATH I76
J 0
(-7150 1925);
DISPLAY 1.021277 (-7150 1925);
PAINT ORANGE (-7150 1925);
DISPLAY INVISIBLE (-7150 1925);
FORCEADD OFFPAGE..1
(-7200 1800);
FORCEPROP 2 LAST $XR0 164 
J 0
(-7452 1800);
DISPLAY 0.638298 (-7452 1800);
PAINT MONO (-7452 1800);
FORCEPROP 2 LAST $XR1 147 
J 0
(-7572 1800);
DISPLAY 0.638298 (-7572 1800);
PAINT MONO (-7572 1800);
FORCEPROP 2 LAST CDS_LIB mstr_standard
J 0
(-7200 1800);
DISPLAY 1.212766 (-7200 1800);
PAINT ORANGE (-7200 1800);
DISPLAY INVISIBLE (-7200 1800);
FORCEPROP 1 LAST OFFPAGE TRUE
J 0
(-6875 1675);
PAINT GREEN (-6875 1675);
DISPLAY INVISIBLE (-6875 1675);
FORCEPROP 1 LAST COMMENT_BODY TRUE
J 0
(-7075 1700);
DISPLAY 1.404255 (-7075 1700);
PAINT PEACH (-7075 1700);
DISPLAY INVISIBLE (-7075 1700);
FORCEPROP 2 LAST PATH I77
J 0
(-7150 1875);
DISPLAY 1.021277 (-7150 1875);
PAINT ORANGE (-7150 1875);
DISPLAY INVISIBLE (-7150 1875);
FORCEADD OFFPAGE..5
R 2
(-1550 3800);
FORCEPROP 2 LAST $XR0 138 
J 0
(-1361 3800);
DISPLAY 0.638298 (-1361 3800);
PAINT MONO (-1361 3800);
FORCEPROP 2 LAST CDS_LIB mstr_standard
J 2
(-1550 3800);
DISPLAY 1.212766 (-1550 3800);
PAINT ORANGE (-1550 3800);
DISPLAY INVISIBLE (-1550 3800);
FORCEPROP 1 LAST OFFPAGE TRUE
J 2
(-1875 3675);
DISPLAY 0.872340 (-1875 3675);
PAINT GREEN (-1875 3675);
DISPLAY INVISIBLE (-1875 3675);
FORCEPROP 1 LAST COMMENT_BODY TRUE
J 2
(-1650 3725);
DISPLAY 0.872340 (-1650 3725);
PAINT GREEN (-1650 3725);
DISPLAY INVISIBLE (-1650 3725);
FORCEPROP 2 LAST PATH I9
J 0
(-1350 3875);
DISPLAY 1.021277 (-1350 3875);
PAINT ORANGE (-1350 3875);
DISPLAY INVISIBLE (-1350 3875);
FORCEADD DESIGN_NOTE..1
(-5350 800);
FORCEPROP 0 LAST L1 SMBUS PULL UP AND SERIES RESISTORS ON SEPARATE PAGE
J 0
(-5525 650);
DISPLAY 1.021277 (-5525 650);
PAINT ORANGE (-5525 650);
FORCEPROP 1 LAST COMMENT_BODY TRUE
J 0
(-5325 900);
DISPLAY 0.978723 (-5325 900);
PAINT ORANGE (-5325 900);
DISPLAY INVISIBLE (-5325 900);
FORCEPROP 2 LAST CDS_LIB mstr_symbols
J 0
(-5350 800);
PAINT ORANGE (-5350 800);
DISPLAY INVISIBLE (-5350 800);
FORCEADD CAD_NOTE..1
(-625 3350);
FORCEPROP 0 LAST L1 PLACE RCOMP RES
J 0
(-775 3225);
DISPLAY 1.021277 (-775 3225);
PAINT ORANGE (-775 3225);
FORCEPROP 0 LAST L2 CLOSE TO PCH
J 0
(-775 3150);
DISPLAY 1.021277 (-775 3150);
PAINT ORANGE (-775 3150);
FORCEPROP 1 LAST COMMENT_BODY TRUE
J 0
(-600 3450);
DISPLAY 0.978723 (-600 3450);
PAINT ORANGE (-600 3450);
DISPLAY INVISIBLE (-600 3450);
FORCEPROP 2 LAST CDS_LIB mstr_symbols
J 0
(-625 3350);
PAINT MONO (-625 3350);
DISPLAY INVISIBLE (-625 3350);
FORCEADD CAD_NOTE..1
(-6950 1000);
FORCEPROP 0 LAST L1 PLACE SERIES TERM RES CLOSE TO PCH
J 0
(-7100 875);
DISPLAY 1.021277 (-7100 875);
PAINT ORANGE (-7100 875);
FORCEPROP 1 LAST COMMENT_BODY TRUE
J 0
(-6925 1100);
DISPLAY 0.978723 (-6925 1100);
PAINT ORANGE (-6925 1100);
DISPLAY INVISIBLE (-6925 1100);
FORCEPROP 2 LAST CDS_LIB mstr_symbols
J 0
(-6950 1000);
PAINT MONO (-6950 1000);
DISPLAY INVISIBLE (-6950 1000);
FORCEADD INTEL_CORP_BPAGE..1
(0 0);
FORCEPROP 1 LAST CDS_CON_LAST_MODIFIED Tue Dec 01 11:51:57 2015
J 0
(-1425 325);
DISPLAY 1.340426 (-1425 325);
PAINT ORANGE (-1425 325);
DISPLAY INVISIBLE (-1425 325);
FORCEPROP 1 LAST CUSTOM_TXT_CDS <CURRENT_DESIGN_SHEET> OF <TOTAL_DESIGN_SHEETS>
J 0
(-500 25);
PAINT GREEN (-500 25);
FORCEPROP 1 LAST CUSTOM_TXT_CDS <CON_LAST_MODIFIED>
J 0
(-1925 350);
PAINT GREEN (-1925 350);
FORCEPROP 2 LAST CUSTOM_TXT_CDS <XR_PAGE_TITLE>
J 0
(-7890 5250);
DISPLAY 0.638298 (-7890 5250);
PAINT PINK (-7890 5250);
DISPLAY INVISIBLE (-7890 5250);
FORCEPROP 1 LAST SCH_TITLE LEWISBURG 7/11 GPIO E-J
J 0
(-7950 50);
DISPLAY 1.212766 (-7950 50);
PAINT YELLOW (-7950 50);
FORCEPROP 1 LAST SCH_ADDRESS1 2200 Mission College Blvd.
J 0
(-3975 125);
DISPLAY 0.617021 (-3975 125);
PAINT YELLOW (-3975 125);
FORCEPROP 1 LAST SCH_ADDRESS2 P.O. BOX 58119
J 0
(-3975 75);
DISPLAY 0.617021 (-3975 75);
PAINT YELLOW (-3975 75);
FORCEPROP 1 LAST SCH_ADDRESS3 Santa Clara, CA 95052-8119
J 0
(-3975 25);
DISPLAY 0.617021 (-3975 25);
PAINT YELLOW (-3975 25);
FORCEPROP 1 LAST SCH_REV 2.420
J 0
(-250 150);
DISPLAY 0.978723 (-250 150);
PAINT YELLOW (-250 150);
FORCEPROP 1 LAST SCH_DEPT BESD
J 1
(-4450 100);
DISPLAY 1.212766 (-4450 100);
PAINT YELLOW (-4450 100);
FORCEPROP 1 LAST SCH_NUMBER H4694802
J 0
(-1300 150);
DISPLAY 1.212766 (-1300 150);
PAINT YELLOW (-1300 150);
FORCEPROP 1 LAST COMMENT_BODY TRUE
J 0
(12 12);
DISPLAY 0.638298 (12 12);
PAINT PEACH (12 12);
DISPLAY INVISIBLE (12 12);
FORCEPROP 2 LAST CDS_LIB mstr_symbols
J 0
(0 0);
PAINT ORANGE (0 0);
DISPLAY INVISIBLE (0 0);
FORCEPROP 2 LAST PAGE_BORDER TRUE
J 0
(-7890 5250);
DISPLAY 0.851064 (-7890 5250);
PAINT PINK (-7890 5250);
DISPLAY INVISIBLE (-7890 5250);
FORCEPROP 2 LAST CDS_XR_PAGE_TITLE CR-120 : @BASEBOARD_FAB2_LIB.BASEBOARD_FAB2(SCH_1):PAGE120
J 0
(-7890 5250);
DISPLAY 0.638298 (-7890 5250);
PAINT PINK (-7890 5250);
DISPLAY INVISIBLE (-7890 5250);
WIRE 16 -1 (-775 2725)(-775 2650);
WIRE 16 -1 (-7150 2750)(-5575 2750);
FORCEPROP 0 LAST SIG_NAME JTAG_PCH_PLD_TCK
J 0
(-7150 2760);
DISPLAY 0.617021 (-7150 2760);
PAINT ORANGE (-7150 2760);
WIRE 16 -1 (-7150 2050)(-6425 2050);
FORCEPROP 0 LAST SIG_NAME FM_ADR_COMPLETE
J 0
(-7150 2060);
DISPLAY 0.617021 (-7150 2060);
PAINT ORANGE (-7150 2060);
WIRE 16 -1 (-7150 3850)(-6475 3850);
FORCEPROP 0 LAST SIG_NAME FM_CPLD_ADR_TRIGGER_N
J 0
(-7150 3860);
DISPLAY 0.617021 (-7150 3860);
PAINT ORANGE (-7150 3860);
WIRE 16 -1 (-6275 3850)(-5575 3850);
FORCEPROP 0 LAST SIG_NAME FM_CPLD_ADR_TRIGGER_R_N
J 0
(-6260 3860);
DISPLAY 0.617021 (-6260 3860);
PAINT ORANGE (-6260 3860);
FORCEPROP 2 LASTPROP $XRERR UNIQUE?
J 0
(-6500 3860);
DISPLAY 0.638298 (-6500 3860);
PAINT MONO (-6500 3860);
DISPLAY INVISIBLE (-6500 3860);
WIRE 16 -1 (-6250 3050)(-5575 3050);
FORCEPROP 0 LAST SIG_NAME TP_PCH_GPP_F12
J 0
(-6235 3060);
DISPLAY 0.617021 (-6235 3060);
PAINT ORANGE (-6235 3060);
FORCEPROP 2 LASTPROP $XRERR UNIQUE?
J 0
(-6490 3050);
DISPLAY 0.638298 (-6490 3050);
PAINT MONO (-6490 3050);
DISPLAY INVISIBLE (-6490 3050);
WIRE 16 -1 (-6225 2050)(-5575 2050);
FORCEPROP 2 LAST SIG_NAME FM_ADR_COMPLETE_R1
J 0
(-6185 2060);
DISPLAY 0.617021 (-6185 2060);
PAINT ORANGE (-6185 2060);
FORCEPROP 2 LASTPROP $XRERR UNIQUE?
J 0
(-6425 2060);
DISPLAY 0.638298 (-6425 2060);
PAINT MONO (-6425 2060);
DISPLAY INVISIBLE (-6425 2060);
WIRE 16 -1 (-7150 3950)(-5575 3950);
FORCEPROP 0 LAST SIG_NAME FM_CPU_MSMI_LVT3_N
J 0
(-7150 3960);
DISPLAY 0.617021 (-7150 3960);
PAINT ORANGE (-7150 3960);
WIRE 16 -1 (-7150 4000)(-5575 4000);
FORCEPROP 0 LAST SIG_NAME IRQ_BMC_PCH_NMI_STBY_N
J 0
(-7150 4010);
DISPLAY 0.617021 (-7150 4010);
PAINT ORANGE (-7150 4010);
WIRE 16 -1 (-7150 3800)(-5575 3800);
FORCEPROP 0 LAST SIG_NAME FM_POST_CARD_PRES_BMC_N
J 0
(-7150 3810);
DISPLAY 0.617021 (-7150 3810);
PAINT ORANGE (-7150 3810);
WIRE 16 -1 (-7150 4050)(-5575 4050);
FORCEPROP 0 LAST SIG_NAME FM_ADR_SMI_GPIO_N
J 0
(-7150 4060);
DISPLAY 0.617021 (-7150 4060);
PAINT ORANGE (-7150 4060);
WIRE 16 -1 (-7150 3900)(-5575 3900);
FORCEPROP 0 LAST SIG_NAME FM_CPU_ERR2_LVT3_N
J 0
(-7150 3910);
DISPLAY 0.617021 (-7150 3910);
PAINT ORANGE (-7150 3910);
WIRE 16 -1 (-7150 2450)(-5575 2450);
FORCEPROP 0 LAST SIG_NAME IRQ_OC_DETECT_N
J 0
(-7150 2460);
DISPLAY 0.617021 (-7150 2460);
PAINT ORANGE (-7150 2460);
WIRE 16 -1 (-7150 2500)(-5575 2500);
FORCEPROP 0 LAST SIG_NAME FM_HSC_TIMER_EXP_N
J 0
(-7150 2510);
DISPLAY 0.617021 (-7150 2510);
PAINT ORANGE (-7150 2510);
WIRE 16 -1 (-7150 2550)(-5575 2550);
FORCEPROP 0 LAST SIG_NAME FM_MP_PS_FAIL_N
J 0
(-7150 2560);
DISPLAY 0.617021 (-7150 2560);
PAINT ORANGE (-7150 2560);
WIRE 16 -1 (-7150 2600)(-5575 2600);
FORCEPROP 0 LAST SIG_NAME FM_MP_PS_REDUNDANT_LOST_N
J 0
(-7150 2610);
DISPLAY 0.617021 (-7150 2610);
PAINT ORANGE (-7150 2610);
WIRE 16 -1 (-7150 3350)(-5575 3350);
FORCEPROP 0 LAST SIG_NAME FM_MEM_THERM_EVENT_PCH_N
J 0
(-7150 3360);
DISPLAY 0.617021 (-7150 3360);
PAINT ORANGE (-7150 3360);
WIRE 16 -1 (-7150 2650)(-5575 2650);
FORCEPROP 0 LAST SIG_NAME FM_BMC_READY_N
J 0
(-7150 2660);
DISPLAY 0.617021 (-7150 2660);
PAINT ORANGE (-7150 2660);
WIRE 16 -1 (-7150 3300)(-5575 3300);
FORCEPROP 0 LAST SIG_NAME FM_BIOS_TOP_SWAP
J 0
(-7150 3310);
DISPLAY 0.617021 (-7150 3310);
PAINT ORANGE (-7150 3310);
WIRE 16 -1 (-7150 3400)(-5575 3400);
FORCEPROP 0 LAST SIG_NAME SMB_LAN_STBY_LVC3_SCL_R2
J 0
(-7150 3410);
DISPLAY 0.617021 (-7150 3410);
PAINT ORANGE (-7150 3410);
WIRE 16 -1 (-7150 3450)(-5575 3450);
FORCEPROP 0 LAST SIG_NAME SMB_LAN_STBY_LVC3_SDA_R2
J 0
(-7150 3460);
DISPLAY 0.617021 (-7150 3460);
PAINT ORANGE (-7150 3460);
WIRE 16 -1 (-7150 1300)(-5575 1300);
FORCEPROP 0 LAST SIG_NAME FAN_TACH2
J 0
(-7150 1310);
DISPLAY 0.617021 (-7150 1310);
PAINT ORANGE (-7150 1310);
WIRE 16 -1 (-7150 1200)(-5575 1200);
FORCEPROP 0 LAST SIG_NAME FAN_TACH0
J 0
(-7150 1210);
DISPLAY 0.617021 (-7150 1210);
PAINT ORANGE (-7150 1210);
WIRE 16 -1 (-7150 1400)(-5575 1400);
FORCEPROP 0 LAST SIG_NAME IRQ_PVCCIN_CPU0_VRHOT_LVC3_N
J 0
(-7150 1410);
DISPLAY 0.617021 (-7150 1410);
PAINT ORANGE (-7150 1410);
WIRE 16 -1 (-7150 1450)(-5575 1450);
FORCEPROP 0 LAST SIG_NAME IRQ_PVCCIN_CPU1_VRHOT_LVC3_N
J 0
(-7150 1460);
DISPLAY 0.617021 (-7150 1460);
PAINT ORANGE (-7150 1460);
WIRE 16 -1 (-7150 2350)(-5575 2350);
FORCEPROP 2 LAST SIG_NAME FM_UARTSW_MSB_N
J 0
(-7150 2360);
DISPLAY 0.617021 (-7150 2360);
PAINT ORANGE (-7150 2360);
WIRE 16 -1 (-7150 1650)(-5575 1650);
FORCEPROP 0 LAST SIG_NAME FAN_PWM_OUT_SYS1
J 0
(-7150 1660);
DISPLAY 0.617021 (-7150 1660);
PAINT ORANGE (-7150 1660);
WIRE 16 -1 (-7150 1600)(-5575 1600);
FORCEPROP 0 LAST SIG_NAME FAN_PWM_OUT_SYS0
J 0
(-7150 1610);
DISPLAY 0.617021 (-7150 1610);
PAINT ORANGE (-7150 1610);
WIRE 16 -1 (-7150 1700)(-5575 1700);
FORCEPROP 0 LAST SIG_NAME FM_CPU0_FIVR_FAULT_LVT3_N
J 0
(-7150 1710);
DISPLAY 0.617021 (-7150 1710);
PAINT ORANGE (-7150 1710);
WIRE 16 -1 (-7150 1750)(-5575 1750);
FORCEPROP 0 LAST SIG_NAME FM_CPU1_FIVR_FAULT_LVT3_N
J 0
(-7150 1760);
DISPLAY 0.617021 (-7150 1760);
PAINT ORANGE (-7150 1760);
WIRE 16 -1 (-7150 1350)(-5575 1350);
FORCEPROP 0 LAST SIG_NAME FAN_TACH3
J 0
(-7150 1360);
DISPLAY 0.617021 (-7150 1360);
PAINT ORANGE (-7150 1360);
WIRE 16 -1 (-7150 1250)(-5575 1250);
FORCEPROP 0 LAST SIG_NAME FAN_TACH1
J 0
(-7150 1260);
DISPLAY 0.617021 (-7150 1260);
PAINT ORANGE (-7150 1260);
WIRE 16 -1 (-7150 3250)(-5575 3250);
FORCEPROP 0 LAST SIG_NAME FM_IE_DISABLE_N
J 0
(-7150 3260);
DISPLAY 0.617021 (-7150 3260);
PAINT ORANGE (-7150 3260);
WIRE 16 -1 (-7150 2800)(-5575 2800);
FORCEPROP 0 LAST SIG_NAME JTAG_PCH_PLD_TDI
J 0
(-7150 2810);
DISPLAY 0.617021 (-7150 2810);
PAINT ORANGE (-7150 2810);
WIRE 16 -1 (-7150 2850)(-5575 2850);
FORCEPROP 0 LAST SIG_NAME JTAG_PCH_PLD_TMS
J 0
(-7150 2860);
DISPLAY 0.617021 (-7150 2860);
PAINT ORANGE (-7150 2860);
WIRE 16 -1 (-7150 2900)(-5575 2900);
FORCEPROP 0 LAST SIG_NAME JTAG_PCH_PLD_TDO
J 0
(-7150 2910);
DISPLAY 0.617021 (-7150 2910);
PAINT ORANGE (-7150 2910);
WIRE 16 -1 (-7150 2700)(-5575 2700);
FORCEPROP 0 LAST SIG_NAME FM_BIOS_USB_RECOVERY
J 0
(-7150 2710);
DISPLAY 0.617021 (-7150 2710);
PAINT ORANGE (-7150 2710);
WIRE 16 -1 (-7150 3200)(-5575 3200);
FORCEPROP 0 LAST SIG_NAME FM_FORCE_ADR_N
J 0
(-7150 3210);
DISPLAY 0.617021 (-7150 3210);
PAINT ORANGE (-7150 3210);
WIRE 16 -1 (-7150 3500)(-5575 3500);
FORCEPROP 0 LAST SIG_NAME IRQ_PCH_NIC_ALERT_N
J 0
(-7150 3510);
DISPLAY 0.617021 (-7150 3510);
PAINT ORANGE (-7150 3510);
WIRE 16 -1 (-7150 3000)(-5575 3000);
FORCEPROP 0 LAST SIG_NAME SGPIO_PCH_SATA_LOAD
J 0
(-7150 3010);
DISPLAY 0.617021 (-7150 3010);
PAINT ORANGE (-7150 3010);
WIRE 16 -1 (-7150 2950)(-5575 2950);
FORCEPROP 0 LAST SIG_NAME SGPIO_PCH_SATA_CLOCK
J 0
(-7150 2960);
DISPLAY 0.617021 (-7150 2960);
PAINT ORANGE (-7150 2960);
WIRE 16 -1 (-7150 3600)(-5575 3600);
FORCEPROP 0 LAST SIG_NAME SGPIO_PCH_SSATA_LOAD
J 0
(-7150 3610);
DISPLAY 0.617021 (-7150 3610);
PAINT ORANGE (-7150 3610);
WIRE 16 -1 (-7150 3550)(-5575 3550);
FORCEPROP 0 LAST SIG_NAME SGPIO_PCH_SSATA_CLOCK
J 0
(-7150 3560);
DISPLAY 0.617021 (-7150 3560);
PAINT ORANGE (-7150 3560);
WIRE 16 -1 (-7150 3100)(-5575 3100);
FORCEPROP 0 LAST SIG_NAME SGPIO_PCH_SATA_DOUT0
J 0
(-7150 3110);
DISPLAY 0.617021 (-7150 3110);
PAINT ORANGE (-7150 3110);
WIRE 16 -1 (-7150 1550)(-5575 1550);
FORCEPROP 0 LAST SIG_NAME FM_THROTTLE_N
J 0
(-7150 1560);
DISPLAY 0.617021 (-7150 1560);
PAINT ORANGE (-7150 1560);
WIRE 16 -1 (-7150 1500)(-5575 1500);
FORCEPROP 0 LAST SIG_NAME FM_CPU1_THERMTRIP_LATCH_LVT3_N
J 0
(-7150 1510);
DISPLAY 0.617021 (-7150 1510);
PAINT ORANGE (-7150 1510);
WIRE 16 -1 (-7150 3700)(-5575 3700);
FORCEPROP 2 LAST SIG_NAME FM_CPU0_RC_ERROR_N
J 0
(-7150 3710);
DISPLAY 0.617021 (-7150 3710);
PAINT ORANGE (-7150 3710);
WIRE 16 -1 (-7150 2300)(-5575 2300);
FORCEPROP 2 LAST SIG_NAME FM_CPU0_RC_EN
J 0
(-7150 2310);
DISPLAY 0.617021 (-7150 2310);
PAINT ORANGE (-7150 2310);
WIRE 16 -1 (-7150 3750)(-5575 3750);
FORCEPROP 2 LAST SIG_NAME FM_CPU1_RC_ERROR_N
J 0
(-7150 3760);
DISPLAY 0.617021 (-7150 3760);
PAINT ORANGE (-7150 3760);
WIRE 16 -1 (-7150 3150)(-5575 3150);
FORCEPROP 0 LAST SIG_NAME LED_PCH_SSATA_HDD_N
J 0
(-7150 3160);
DISPLAY 0.617021 (-7150 3160);
PAINT ORANGE (-7150 3160);
WIRE 16 -1 (-7150 2250)(-5575 2250);
FORCEPROP 2 LAST SIG_NAME FM_SOL_UART_CH_SEL
J 0
(-7150 2260);
DISPLAY 0.617021 (-7150 2260);
PAINT ORANGE (-7150 2260);
WIRE 16 -1 (-7150 2200)(-5575 2200);
FORCEPROP 2 LAST SIG_NAME IRQ_FORCE_NM_THROTTLE_N
J 0
(-7150 2210);
DISPLAY 0.617021 (-7150 2210);
PAINT ORANGE (-7150 2210);
WIRE 16 -1 (-7150 2150)(-5575 2150);
FORCEPROP 2 LAST SIG_NAME FM_BIOS_SMI_ACTIVE_N
J 0
(-7150 2160);
DISPLAY 0.617021 (-7150 2160);
PAINT ORANGE (-7150 2160);
WIRE 16 -1 (-7150 2100)(-5575 2100);
FORCEPROP 2 LAST SIG_NAME FM_NMI_EVENT_N
J 0
(-7150 2110);
DISPLAY 0.617021 (-7150 2110);
PAINT ORANGE (-7150 2110);
WIRE 16 -1 (-7150 2000)(-5575 2000);
FORCEPROP 0 LAST SIG_NAME FM_BOARD_SKU_ID4
J 0
(-7150 2010);
DISPLAY 0.617021 (-7150 2010);
PAINT ORANGE (-7150 2010);
WIRE 16 -1 (-7150 1900)(-5575 1900);
FORCEPROP 0 LAST SIG_NAME FM_BOARD_SKU_ID2
J 0
(-7150 1910);
DISPLAY 0.617021 (-7150 1910);
PAINT ORANGE (-7150 1910);
WIRE 16 -1 (-7150 1950)(-5575 1950);
FORCEPROP 0 LAST SIG_NAME FM_BOARD_SKU_ID3
J 0
(-7150 1960);
DISPLAY 0.617021 (-7150 1960);
PAINT ORANGE (-7150 1960);
WIRE 16 -1 (-7150 1850)(-5575 1850);
FORCEPROP 0 LAST SIG_NAME FM_BOARD_SKU_ID1
J 0
(-7150 1860);
DISPLAY 0.617021 (-7150 1860);
PAINT ORANGE (-7150 1860);
WIRE 16 -1 (-7150 1800)(-5575 1800);
FORCEPROP 0 LAST SIG_NAME FM_BOARD_SKU_ID0
J 0
(-7150 1810);
DISPLAY 0.617021 (-7150 1810);
PAINT ORANGE (-7150 1810);
WIRE 16 -1 (-7150 4150)(-5575 4150);
FORCEPROP 0 LAST SIG_NAME FM_OC0_USB_N
J 0
(-7150 4160);
DISPLAY 0.617021 (-7150 4160);
PAINT ORANGE (-7150 4160);
WIRE 16 -1 (-7150 4200)(-5575 4200);
FORCEPROP 0 LAST SIG_NAME IRQ_BMC_PCH_SCI_LPC_N
J 0
(-7150 4210);
DISPLAY 0.617021 (-7150 4210);
PAINT ORANGE (-7150 4210);
WIRE 16 -1 (-7150 4250)(-5575 4250);
FORCEPROP 0 LAST SIG_NAME IRQ_BMC_PCH_SMI_LPC_N
J 0
(-7150 4260);
DISPLAY 0.617021 (-7150 4260);
PAINT ORANGE (-7150 4260);
WIRE 16 -1 (-7150 4300)(-5575 4300);
FORCEPROP 0 LAST SIG_NAME IRQ_UV_DETECT_N
J 0
(-7150 4310);
DISPLAY 0.617021 (-7150 4310);
PAINT ORANGE (-7150 4310);
WIRE 16 -1 (-7150 4100)(-5575 4100);
FORCEPROP 0 LAST SIG_NAME LED_PCH_SATA_HDD_N
J 0
(-7150 4110);
DISPLAY 0.617021 (-7150 4110);
PAINT ORANGE (-7150 4110);
WIRE 16 -1 (-2375 2100)(-1625 2100);
FORCEPROP 2 LAST SIG_NAME TP_PCH_GPP_J17
J 0
(-2225 2110);
DISPLAY 0.617021 (-2225 2110);
PAINT ORANGE (-2225 2110);
FORCEPROP 2 LASTPROP $XRERR UNIQUE?
J 0
(-1595 2100);
DISPLAY 0.638298 (-1595 2100);
PAINT MONO (-1595 2100);
DISPLAY INVISIBLE (-1595 2100);
WIRE 16 -1 (-2375 2200)(-1625 2200);
FORCEPROP 2 LAST SIG_NAME TP_PCH_GPP_J19
J 0
(-2225 2210);
DISPLAY 0.617021 (-2225 2210);
PAINT ORANGE (-2225 2210);
FORCEPROP 2 LASTPROP $XRERR UNIQUE?
J 0
(-1595 2200);
DISPLAY 0.638298 (-1595 2200);
PAINT MONO (-1595 2200);
DISPLAY INVISIBLE (-1595 2200);
WIRE 16 -1 (-2375 2300)(-1625 2300);
FORCEPROP 2 LAST SIG_NAME TP_PCH_GPP_J21
J 0
(-2225 2310);
DISPLAY 0.617021 (-2225 2310);
PAINT ORANGE (-2225 2310);
FORCEPROP 2 LASTPROP $XRERR UNIQUE?
J 0
(-1595 2300);
DISPLAY 0.638298 (-1595 2300);
PAINT MONO (-1595 2300);
DISPLAY INVISIBLE (-1595 2300);
WIRE 16 -1 (-2375 2400)(-1625 2400);
FORCEPROP 2 LAST SIG_NAME TP_PCH_GPP_J23
J 0
(-2225 2410);
DISPLAY 0.617021 (-2225 2410);
PAINT ORANGE (-2225 2410);
FORCEPROP 2 LASTPROP $XRERR UNIQUE?
J 0
(-1595 2400);
DISPLAY 0.638298 (-1595 2400);
PAINT MONO (-1595 2400);
DISPLAY INVISIBLE (-1595 2400);
WIRE 16 -1 (-2375 3850)(-1625 3850);
FORCEPROP 0 LAST SIG_NAME SMB_SENSOR_STBY_LVC3_SDA_R1
J 0
(-2225 3860);
DISPLAY 0.617021 (-2225 3860);
PAINT ORANGE (-2225 3860);
WIRE 16 -1 (-2375 2950)(-1575 2950);
FORCEPROP 0 LAST SIG_NAME FM_10GBE_LOM_DISABLE_N
J 0
(-2225 2960);
DISPLAY 0.617021 (-2225 2960);
PAINT ORANGE (-2225 2960);
WIRE 16 -1 (-2375 2900)(-1575 2900);
FORCEPROP 0 LAST SIG_NAME PU_10GBE_LOM_PCI_DISABLE_N
J 0
(-2225 2910);
DISPLAY 0.617021 (-2225 2910);
PAINT ORANGE (-2225 2910);
WIRE 16 -1 (-2375 3900)(-1575 3900);
FORCEPROP 0 LAST SIG_NAME PU_ADR_TIMER_HOLD_OFF_N
J 0
(-2225 3910);
DISPLAY 0.617021 (-2225 3910);
PAINT ORANGE (-2225 3910);
WIRE 16 -1 (-2375 2650)(-1575 2650);
FORCEPROP 0 LAST SIG_NAME JTAG_PCH_GBE_TDI
J 0
(-2225 2660);
DISPLAY 0.617021 (-2225 2660);
PAINT ORANGE (-2225 2660);
WIRE 16 -1 (-2375 2600)(-1600 2600);
FORCEPROP 0 LAST SIG_NAME JTAG_PCH_GBE_TMS
J 0
(-2225 2610);
DISPLAY 0.617021 (-2225 2610);
PAINT ORANGE (-2225 2610);
WIRE 16 -1 (-2375 2500)(-1600 2500);
FORCEPROP 0 LAST SIG_NAME JTAG_PCH_GBE_TDO
J 0
(-2225 2510);
DISPLAY 0.617021 (-2225 2510);
PAINT ORANGE (-2225 2510);
WIRE 16 -1 (-2375 2550)(-1600 2550);
FORCEPROP 0 LAST SIG_NAME JTAG_PCH_GBE_CLK
J 0
(-2225 2560);
DISPLAY 0.617021 (-2225 2560);
PAINT ORANGE (-2225 2560);
WIRE 16 -1 (-2375 3650)(-1600 3650);
FORCEPROP 0 LAST SIG_NAME SMB_VR_STBY_LVC3_SCL_R1
J 0
(-2225 3660);
DISPLAY 0.617021 (-2225 3660);
PAINT ORANGE (-2225 3660);
WIRE 16 -1 (-2375 2850)(-1600 2850);
FORCEPROP 0 LAST SIG_NAME JTAG_PCH_GBE_TRST_N
J 0
(-2225 2860);
DISPLAY 0.617021 (-2225 2860);
PAINT ORANGE (-2225 2860);
WIRE 16 -1 (-2375 3200)(-1600 3200);
FORCEPROP 0 LAST SIG_NAME FM_BACKUP_BIOS_SEL_N
J 0
(-2225 3210);
DISPLAY 0.617021 (-2225 3210);
PAINT ORANGE (-2225 3210);
WIRE 16 -1 (-2375 3600)(-1600 3600);
FORCEPROP 0 LAST SIG_NAME LED_POSTCODE_7
J 0
(-2225 3610);
DISPLAY 0.617021 (-2225 3610);
PAINT ORANGE (-2225 3610);
WIRE 16 -1 (-2375 3550)(-1600 3550);
FORCEPROP 0 LAST SIG_NAME LED_POSTCODE_6
J 0
(-2225 3560);
DISPLAY 0.617021 (-2225 3560);
PAINT ORANGE (-2225 3560);
WIRE 16 -1 (-2375 3500)(-1600 3500);
FORCEPROP 0 LAST SIG_NAME LED_POSTCODE_5
J 0
(-2225 3510);
DISPLAY 0.617021 (-2225 3510);
PAINT ORANGE (-2225 3510);
WIRE 16 -1 (-2375 3450)(-1600 3450);
FORCEPROP 0 LAST SIG_NAME LED_POSTCODE_4
J 0
(-2225 3460);
DISPLAY 0.617021 (-2225 3460);
PAINT ORANGE (-2225 3460);
WIRE 16 -1 (-2375 3400)(-1600 3400);
FORCEPROP 0 LAST SIG_NAME LED_POSTCODE_3
J 0
(-2225 3410);
DISPLAY 0.617021 (-2225 3410);
PAINT ORANGE (-2225 3410);
WIRE 16 -1 (-2375 3350)(-1600 3350);
FORCEPROP 0 LAST SIG_NAME LED_POSTCODE_2
J 0
(-2225 3360);
DISPLAY 0.617021 (-2225 3360);
PAINT ORANGE (-2225 3360);
WIRE 16 -1 (-2375 3300)(-1600 3300);
FORCEPROP 0 LAST SIG_NAME LED_POSTCODE_1
J 0
(-2225 3310);
DISPLAY 0.617021 (-2225 3310);
PAINT ORANGE (-2225 3310);
WIRE 16 -1 (-2375 3250)(-1600 3250);
FORCEPROP 0 LAST SIG_NAME LED_POSTCODE_0
J 0
(-2225 3260);
DISPLAY 0.617021 (-2225 3260);
PAINT ORANGE (-2225 3260);
WIRE 16 -1 (-2375 3150)(-1575 3150);
FORCEPROP 0 LAST SIG_NAME FM_UARTSW_LSB_N
J 0
(-2225 3160);
DISPLAY 0.617021 (-2225 3160);
PAINT ORANGE (-2225 3160);
WIRE 16 -1 (-2375 2700)(-1575 2700);
FORCEPROP 0 LAST SIG_NAME IRQ_DIMM_SAVE_LVT3_N
J 0
(-2225 2710);
DISPLAY 0.617021 (-2225 2710);
PAINT ORANGE (-2225 2710);
WIRE 16 -1 (-2375 2750)(-1600 2750);
FORCEPROP 0 LAST SIG_NAME IRQ_BOARD_BMC_ALERT_N
J 0
(-2225 2760);
DISPLAY 0.617021 (-2225 2760);
PAINT ORANGE (-2225 2760);
WIRE 16 -1 (-2375 3000)(-1575 3000);
FORCEPROP 0 LAST SIG_NAME FM_BIOS_MRC_DEBUG_MSG_DIS_N
J 0
(-2225 3010);
DISPLAY 0.617021 (-2225 3010);
PAINT ORANGE (-2225 3010);
WIRE 16 -1 (-2375 4050)(-1600 4050);
FORCEPROP 0 LAST SIG_NAME FM_OC_DETECT_EN_N
J 0
(-2225 4060);
DISPLAY 0.617021 (-2225 4060);
PAINT ORANGE (-2225 4060);
WIRE 16 -1 (-2375 1250)(-1600 1250);
FORCEPROP 2 LAST SIG_NAME LED_GBE_P0_0
J 0
(-2225 1260);
DISPLAY 0.617021 (-2225 1260);
PAINT ORANGE (-2225 1260);
WIRE 16 -1 (-2375 1300)(-1600 1300);
FORCEPROP 2 LAST SIG_NAME LED_GBE_P0_1
J 0
(-2225 1310);
DISPLAY 0.617021 (-2225 1310);
PAINT ORANGE (-2225 1310);
WIRE 16 -1 (-2375 1350)(-1600 1350);
FORCEPROP 2 LAST SIG_NAME LED_GBE_P1_0
J 0
(-2225 1360);
DISPLAY 0.617021 (-2225 1360);
PAINT ORANGE (-2225 1360);
WIRE 16 -1 (-2375 1400)(-1600 1400);
FORCEPROP 2 LAST SIG_NAME LED_GBE_P1_1
J 0
(-2225 1410);
DISPLAY 0.617021 (-2225 1410);
PAINT ORANGE (-2225 1410);
WIRE 16 -1 (-2375 1600)(-1600 1600);
FORCEPROP 2 LAST SIG_NAME LED_GBE_P3_1
J 0
(-2225 1610);
DISPLAY 0.617021 (-2225 1610);
PAINT ORANGE (-2225 1610);
WIRE 16 -1 (-2375 1650)(-1600 1650);
FORCEPROP 0 LAST SIG_NAME SMB_PCH_MEZZ_LOM0_SCL
J 0
(-2225 1660);
DISPLAY 0.617021 (-2225 1660);
PAINT ORANGE (-2225 1660);
WIRE 16 -1 (-2375 1750)(-1600 1750);
FORCEPROP 0 LAST SIG_NAME SMB_PCH_MEZZ_LOM1_SCL
J 0
(-2225 1760);
DISPLAY 0.617021 (-2225 1760);
PAINT ORANGE (-2225 1760);
WIRE 16 -1 (-2375 1700)(-1625 1700);
FORCEPROP 0 LAST SIG_NAME SMB_PCH_MEZZ_LOM0_SDA
J 0
(-2225 1710);
DISPLAY 0.617021 (-2225 1710);
PAINT ORANGE (-2225 1710);
WIRE 16 -1 (-2375 1800)(-1625 1800);
FORCEPROP 0 LAST SIG_NAME SMB_PCH_MEZZ_LOM1_SDA
J 0
(-2225 1810);
DISPLAY 0.617021 (-2225 1810);
PAINT ORANGE (-2225 1810);
WIRE 16 -1 (-2375 2350)(-1575 2350);
FORCEPROP 0 LAST SIG_NAME FM_GBE3_LVC3_MOD_ABS
J 0
(-2225 2360);
DISPLAY 0.617021 (-2225 2360);
PAINT ORANGE (-2225 2360);
WIRE 16 -1 (-2375 2250)(-1575 2250);
FORCEPROP 0 LAST SIG_NAME FM_GBE2_LVC3_MOD_ABS
J 0
(-2225 2260);
DISPLAY 0.617021 (-2225 2260);
PAINT ORANGE (-2225 2260);
WIRE 16 -1 (-2375 2150)(-1575 2150);
FORCEPROP 0 LAST SIG_NAME FM_GBE1_LVC3_MOD_ABS
J 0
(-2225 2160);
DISPLAY 0.617021 (-2225 2160);
PAINT ORANGE (-2225 2160);
WIRE 16 -1 (-2375 2050)(-1575 2050);
FORCEPROP 0 LAST SIG_NAME FM_GBE0_LVC3_MOD_ABS
J 0
(-2225 2060);
DISPLAY 0.617021 (-2225 2060);
PAINT ORANGE (-2225 2060);
WIRE 16 -1 (-2375 1450)(-1600 1450);
FORCEPROP 2 LAST SIG_NAME LED_GBE_P2_0
J 0
(-2225 1460);
DISPLAY 0.617021 (-2225 1460);
PAINT ORANGE (-2225 1460);
WIRE 16 -1 (-2375 1500)(-1600 1500);
FORCEPROP 2 LAST SIG_NAME LED_GBE_P2_1
J 0
(-2225 1510);
DISPLAY 0.617021 (-2225 1510);
PAINT ORANGE (-2225 1510);
WIRE 16 -1 (-2375 1550)(-1600 1550);
FORCEPROP 2 LAST SIG_NAME LED_GBE_P3_0
J 0
(-2225 1560);
DISPLAY 0.617021 (-2225 1560);
PAINT ORANGE (-2225 1560);
WIRE 16 -1 (-2375 1850)(-1600 1850);
FORCEPROP 0 LAST SIG_NAME SMB_PCH_MEZZ_LOM2_SCL
J 0
(-2225 1860);
DISPLAY 0.617021 (-2225 1860);
PAINT ORANGE (-2225 1860);
WIRE 16 -1 (-2375 1900)(-1625 1900);
FORCEPROP 0 LAST SIG_NAME SMB_PCH_MEZZ_LOM2_SDA
J 0
(-2225 1910);
DISPLAY 0.617021 (-2225 1910);
PAINT ORANGE (-2225 1910);
WIRE 16 -1 (-2375 2000)(-1625 2000);
FORCEPROP 0 LAST SIG_NAME SMB_PCH_MEZZ_LOM3_SDA
J 0
(-2225 2010);
DISPLAY 0.617021 (-2225 2010);
PAINT ORANGE (-2225 2010);
WIRE 16 -1 (-2375 1950)(-1600 1950);
FORCEPROP 0 LAST SIG_NAME SMB_PCH_MEZZ_LOM3_SCL
J 0
(-2225 1960);
DISPLAY 0.617021 (-2225 1960);
PAINT ORANGE (-2225 1960);
WIRE 16 -1 (-2375 3750)(-1600 3750);
FORCEPROP 0 LAST SIG_NAME FM_FLASH_ATTACH_CFG_STRAP
J 0
(-2225 3760);
DISPLAY 0.617021 (-2225 3760);
PAINT ORANGE (-2225 3760);
WIRE 16 -1 (-2375 2800)(-1625 2800);
FORCEPROP 0 LAST SIG_NAME FM_CPU1_RC_ERROR_N
J 0
(-2225 2810);
DISPLAY 0.617021 (-2225 2810);
PAINT ORANGE (-2225 2810);
WIRE 16 -1 (-2375 3950)(-1600 3950);
FORCEPROP 0 LAST SIG_NAME SMB_LAN_STBY_LVC3_SCL_R1
J 0
(-2225 3960);
DISPLAY 0.617021 (-2225 3960);
PAINT ORANGE (-2225 3960);
WIRE 16 -1 (-2375 4000)(-1625 4000);
FORCEPROP 0 LAST SIG_NAME SMB_LAN_STBY_LVC3_SDA_R1
J 0
(-2225 4010);
DISPLAY 0.617021 (-2225 4010);
PAINT ORANGE (-2225 4010);
WIRE 16 -1 (-2375 3700)(-1625 3700);
FORCEPROP 0 LAST SIG_NAME SMB_VR_STBY_LVC3_SDA_R1
J 0
(-2225 3710);
DISPLAY 0.617021 (-2225 3710);
PAINT ORANGE (-2225 3710);
WIRE 16 -1 (-2375 3800)(-1600 3800);
FORCEPROP 0 LAST SIG_NAME SMB_SENSOR_STBY_LVC3_SCL_R1
J 0
(-2225 3810);
DISPLAY 0.617021 (-2225 3810);
PAINT ORANGE (-2225 3810);
WIRE 16 -1 (-2375 3050)(-775 3050);
FORCEPROP 2 LAST SIG_NAME A_RCOMP_3P3
J 0
(-2225 3060);
DISPLAY 0.617021 (-2225 3060);
PAINT ORANGE (-2225 3060);
FORCEPROP 2 LASTPROP $XRERR UNIQUE?
J 0
(-2465 3060);
DISPLAY 0.638298 (-2465 3060);
PAINT MONO (-2465 3060);
DISPLAY INVISIBLE (-2465 3060);
WIRE 16 -1 (-775 3050)(-775 2925);
WIRE 16 -1 (-2375 4200)(-1575 4200);
FORCEPROP 0 LAST SIG_NAME FM_BIOS_SMI_ACTIVE_N
J 0
(-2225 4210);
DISPLAY 0.617021 (-2225 4210);
PAINT ORANGE (-2225 4210);
WIRE 16 -1 (-2375 4150)(-1575 4150);
FORCEPROP 0 LAST SIG_NAME FM_BMC_NMI_N
J 0
(-2225 4160);
DISPLAY 0.617021 (-2225 4160);
PAINT ORANGE (-2225 4160);
WIRE 16 -1 (-2375 4300)(-1575 4300);
FORCEPROP 0 LAST SIG_NAME FM_SSATA_PCIE_M2_SEL
J 0
(-2225 4310);
DISPLAY 0.617021 (-2225 4310);
PAINT ORANGE (-2225 4310);
WIRE 16 -1 (-2375 4250)(-1575 4250);
FORCEPROP 0 LAST SIG_NAME FM_PCH_BMC_THERMTRIP_N
J 0
(-2225 4260);
DISPLAY 0.617021 (-2225 4260);
PAINT ORANGE (-2225 4260);
WIRE 16 -1 (-2375 4100)(-1600 4100);
FORCEPROP 0 LAST SIG_NAME FP_PWR_ID_LED_N
J 0
(-2225 4110);
DISPLAY 0.617021 (-2225 4110);
PAINT ORANGE (-2225 4110);
FORCENOTE
ROOM=SB
(-7800 275) 0;
DISPLAY LEFT (-7800 275);
DISPLAY 1.021277 (-7800 275);
PAINT PURPLE (-7800 275);
QUIT
